G04 ================== begin FILE IDENTIFICATION RECORD ==================*
G04 Layout Name:  D:/<user>/Wistron_project/16315-1/gbr/16315-1.brd*
G04 Film Name:    BMASK*
G04 File Format:  Gerber RS274X*
G04 File Origin:  Cadence Allegro 16.5-S056*
G04 Origin Date:  Fri Jun 09 15:30:06 2017*
G04 *
G04 Layer:  VIA CLASS/SOLDERMASK_BOTTOM*
G04 Layer:  PIN/SOLDERMASK_BOTTOM*
G04 Layer:  PACKAGE GEOMETRY/SOLDERMASK_BOTTOM*
G04 Layer:  DRAWING FORMAT/LAYER_PCB_STORY*
G04 Layer:  DRAWING FORMAT/LAYER_SOLDER_B*
G04 Layer:  BOARD GEOMETRY/SOLDERMASK_BOTTOM*
G04 *
G04 Offset:    (0.00 0.00)*
G04 Mirror:    No*
G04 Mode:      Positive*
G04 Rotation:  0*
G04 FullContactRelief:  No*
G04 UndefLineWidth:     6.00*
G04 ================== end FILE IDENTIFICATION RECORD ====================*
%FSLAX35Y35*MOIN*%
%IR0*IPPOS*OFA0.00000B0.00000*MIA0B0*SFA1.00000B1.00000*%
%AMMACRO55*
4,1,40,.011,.007,
.011,-.007,
.010939,-.007695,
.010759,-.008368,
.010464,-.009,
.010064,-.009571,
.009571,-.010064,
.009,-.010464,
.008368,-.010759,
.007695,-.010939,
.007,-.011,
-.007,-.011,
-.007695,-.010939,
-.008368,-.010759,
-.009,-.010464,
-.009571,-.010064,
-.010064,-.009571,
-.010464,-.009,
-.010759,-.008368,
-.010939,-.007695,
-.011,-.007,
-.011,.007,
-.010939,.007695,
-.010759,.008368,
-.010464,.009,
-.010064,.009571,
-.009571,.010064,
-.009,.010464,
-.008368,.010759,
-.007695,.010939,
-.007,.011,
.007,.011,
.007695,.010939,
.008368,.010759,
.009,.010464,
.009571,.010064,
.010064,.009571,
.010464,.009,
.010759,.008368,
.010939,.007695,
.011,.007,
0.0*
%
%ADD55MACRO55*%
%AMMACRO41*
4,1,40,.013,-.017,
-.013,-.017,
-.013695,-.016939,
-.014368,-.016759,
-.015,-.016464,
-.015571,-.016064,
-.016064,-.015571,
-.016464,-.015,
-.016759,-.014368,
-.016939,-.013695,
-.017,-.013,
-.017,.013,
-.016939,.013695,
-.016759,.014368,
-.016464,.015,
-.016064,.015571,
-.015571,.016064,
-.015,.016464,
-.014368,.016759,
-.013695,.016939,
-.013,.017,
.013,.017,
.013695,.016939,
.014368,.016759,
.015,.016464,
.015571,.016064,
.016064,.015571,
.016464,.015,
.016759,.014368,
.016939,.013695,
.017,.013,
.017,-.013,
.016939,-.013695,
.016759,-.014368,
.016464,-.015,
.016064,-.015571,
.015571,-.016064,
.015,-.016464,
.014368,-.016759,
.013695,-.016939,
.013,-.017,
0.0*
%
%ADD41MACRO41*%
%AMMACRO17*
4,1,40,-.017,-.013,
-.017,.013,
-.016939,.013695,
-.016759,.014368,
-.016464,.015,
-.016064,.015571,
-.015571,.016064,
-.015,.016464,
-.014368,.016759,
-.013695,.016939,
-.013,.017,
.013,.017,
.013695,.016939,
.014368,.016759,
.015,.016464,
.015571,.016064,
.016064,.015571,
.016464,.015,
.016759,.014368,
.016939,.013695,
.017,.013,
.017,-.013,
.016939,-.013695,
.016759,-.014368,
.016464,-.015,
.016064,-.015571,
.015571,-.016064,
.015,-.016464,
.014368,-.016759,
.013695,-.016939,
.013,-.017,
-.013,-.017,
-.013695,-.016939,
-.014368,-.016759,
-.015,-.016464,
-.015571,-.016064,
-.016064,-.015571,
-.016464,-.015,
-.016759,-.014368,
-.016939,-.013695,
-.017,-.013,
0.0*
%
%ADD17MACRO17*%
%ADD48R,.01X.007*%
%ADD69R,.007X.01*%
%ADD11C,.02*%
%ADD49C,.03*%
%ADD80R,.08X.127*%
%ADD30C,.022*%
%ADD65C,.032*%
%ADD53R,.127X.08*%
%ADD77C,.042*%
%ADD36C,.024*%
%ADD31C,.016*%
%ADD21C,.053*%
%ADD13C,.08*%
%ADD20C,.037*%
%ADD79C,.048*%
%ADD78C,.093*%
%ADD50C,.094*%
%ADD14C,.086*%
%ADD58R,.062X.062*%
%ADD19C,.087*%
%ADD51C,.097*%
%AMMACRO56*
4,1,40,.007,-.011,
-.007,-.011,
-.007695,-.010939,
-.008368,-.010759,
-.009,-.010464,
-.009571,-.010064,
-.010064,-.009571,
-.010464,-.009,
-.010759,-.008368,
-.010939,-.007695,
-.011,-.007,
-.011,.007,
-.010939,.007695,
-.010759,.008368,
-.010464,.009,
-.010064,.009571,
-.009571,.010064,
-.009,.010464,
-.008368,.010759,
-.007695,.010939,
-.007,.011,
.007,.011,
.007695,.010939,
.008368,.010759,
.009,.010464,
.009571,.010064,
.010064,.009571,
.010464,.009,
.010759,.008368,
.010939,.007695,
.011,.007,
.011,-.007,
.010939,-.007695,
.010759,-.008368,
.010464,-.009,
.010064,-.009571,
.009571,-.010064,
.009,-.010464,
.008368,-.010759,
.007695,-.010939,
.007,-.011,
0.0*
%
%ADD56MACRO56*%
%AMMACRO32*
4,1,40,-.011,-.007,
-.011,.007,
-.010939,.007695,
-.010759,.008368,
-.010464,.009,
-.010064,.009571,
-.009571,.010064,
-.009,.010464,
-.008368,.010759,
-.007695,.010939,
-.007,.011,
.007,.011,
.007695,.010939,
.008368,.010759,
.009,.010464,
.009571,.010064,
.010064,.009571,
.010464,.009,
.010759,.008368,
.010939,.007695,
.011,.007,
.011,-.007,
.010939,-.007695,
.010759,-.008368,
.010464,-.009,
.010064,-.009571,
.009571,-.010064,
.009,-.010464,
.008368,-.010759,
.007695,-.010939,
.007,-.011,
-.007,-.011,
-.007695,-.010939,
-.008368,-.010759,
-.009,-.010464,
-.009571,-.010064,
-.010064,-.009571,
-.010464,-.009,
-.010759,-.008368,
-.010939,-.007695,
-.011,-.007,
0.0*
%
%ADD32MACRO32*%
%AMMACRO43*
4,1,40,-.012,-.008,
-.012,.008,
-.011939,.008695,
-.011759,.009368,
-.011464,.01,
-.011064,.010571,
-.010571,.011064,
-.01,.011464,
-.009368,.011759,
-.008695,.011939,
-.008,.012,
.008,.012,
.008695,.011939,
.009368,.011759,
.01,.011464,
.010571,.011064,
.011064,.010571,
.011464,.01,
.011759,.009368,
.011939,.008695,
.012,.008,
.012,-.008,
.011939,-.008695,
.011759,-.009368,
.011464,-.01,
.011064,-.010571,
.010571,-.011064,
.01,-.011464,
.009368,-.011759,
.008695,-.011939,
.008,-.012,
-.008,-.012,
-.008695,-.011939,
-.009368,-.011759,
-.01,-.011464,
-.010571,-.011064,
-.011064,-.010571,
-.011464,-.01,
-.011759,-.009368,
-.011939,-.008695,
-.012,-.008,
0.0*
%
%ADD43MACRO43*%
%AMMACRO74*
4,1,40,-.008,.012,
.008,.012,
.008695,.011939,
.009368,.011759,
.01,.011464,
.010571,.011064,
.011064,.010571,
.011464,.01,
.011759,.009368,
.011939,.008695,
.012,.008,
.012,-.008,
.011939,-.008695,
.011759,-.009368,
.011464,-.01,
.011064,-.010571,
.010571,-.011064,
.01,-.011464,
.009368,-.011759,
.008695,-.011939,
.008,-.012,
-.008,-.012,
-.008695,-.011939,
-.009368,-.011759,
-.01,-.011464,
-.010571,-.011064,
-.011064,-.010571,
-.011464,-.01,
-.011759,-.009368,
-.011939,-.008695,
-.012,-.008,
-.012,.008,
-.011939,.008695,
-.011759,.009368,
-.011464,.01,
-.011064,.010571,
-.010571,.011064,
-.01,.011464,
-.009368,.011759,
-.008695,.011939,
-.008,.012,
0.0*
%
%ADD74MACRO74*%
%AMMACRO26*
4,1,40,-.013,.017,
.013,.017,
.013695,.016939,
.014368,.016759,
.015,.016464,
.015571,.016064,
.016064,.015571,
.016464,.015,
.016759,.014368,
.016939,.013695,
.017,.013,
.017,-.013,
.016939,-.013695,
.016759,-.014368,
.016464,-.015,
.016064,-.015571,
.015571,-.016064,
.015,-.016464,
.014368,-.016759,
.013695,-.016939,
.013,-.017,
-.013,-.017,
-.013695,-.016939,
-.014368,-.016759,
-.015,-.016464,
-.015571,-.016064,
-.016064,-.015571,
-.016464,-.015,
-.016759,-.014368,
-.016939,-.013695,
-.017,-.013,
-.017,.013,
-.016939,.013695,
-.016759,.014368,
-.016464,.015,
-.016064,.015571,
-.015571,.016064,
-.015,.016464,
-.014368,.016759,
-.013695,.016939,
-.013,.017,
0.0*
%
%ADD26MACRO26*%
%AMMACRO66*
4,1,40,.017,.013,
.017,-.013,
.016939,-.013695,
.016759,-.014368,
.016464,-.015,
.016064,-.015571,
.015571,-.016064,
.015,-.016464,
.014368,-.016759,
.013695,-.016939,
.013,-.017,
-.013,-.017,
-.013695,-.016939,
-.014368,-.016759,
-.015,-.016464,
-.015571,-.016064,
-.016064,-.015571,
-.016464,-.015,
-.016759,-.014368,
-.016939,-.013695,
-.017,-.013,
-.017,.013,
-.016939,.013695,
-.016759,.014368,
-.016464,.015,
-.016064,.015571,
-.015571,.016064,
-.015,.016464,
-.014368,.016759,
-.013695,.016939,
-.013,.017,
.013,.017,
.013695,.016939,
.014368,.016759,
.015,.016464,
.015571,.016064,
.016064,.015571,
.016464,.015,
.016759,.014368,
.016939,.013695,
.017,.013,
0.0*
%
%ADD66MACRO66*%
%AMMACRO35*
4,1,6,.025,-.0135,
.005,.0065,
.005,.0135,
-.005,.0135,
-.005,.0065,
-.025,-.0135,
.025,-.0135,
0.0*
%
%ADD35MACRO35*%
%AMMACRO63*
4,1,6,-.0135,-.005,
-.0065,-.005,
.0135,-.025,
.0135,.025,
-.0065,.005,
-.0135,.005,
-.0135,-.005,
0.0*
%
%ADD63MACRO63*%
%AMMACRO57*
4,1,40,.007,-.011,
-.007,-.011,
-.007695,-.010939,
-.008368,-.010759,
-.009,-.010464,
-.009571,-.010064,
-.010064,-.009571,
-.010464,-.009,
-.010759,-.008368,
-.010939,-.007695,
-.011,-.007,
-.011,.007,
-.010939,.007695,
-.010759,.008368,
-.010464,.009,
-.010064,.009571,
-.009571,.010064,
-.009,.010464,
-.008368,.010759,
-.007695,.010939,
-.007,.011,
.007,.011,
.007695,.010939,
.008368,.010759,
.009,.010464,
.009571,.010064,
.010064,.009571,
.010464,.009,
.010759,.008368,
.010939,.007695,
.011,.007,
.011,-.007,
.010939,-.007695,
.010759,-.008368,
.010464,-.009,
.010064,-.009571,
.009571,-.010064,
.009,-.010464,
.008368,-.010759,
.007695,-.010939,
.007,-.011,
0.0*
%
%ADD57MACRO57*%
%AMMACRO33*
4,1,40,-.011,-.007,
-.011,.007,
-.010939,.007695,
-.010759,.008368,
-.010464,.009,
-.010064,.009571,
-.009571,.010064,
-.009,.010464,
-.008368,.010759,
-.007695,.010939,
-.007,.011,
.007,.011,
.007695,.010939,
.008368,.010759,
.009,.010464,
.009571,.010064,
.010064,.009571,
.010464,.009,
.010759,.008368,
.010939,.007695,
.011,.007,
.011,-.007,
.010939,-.007695,
.010759,-.008368,
.010464,-.009,
.010064,-.009571,
.009571,-.010064,
.009,-.010464,
.008368,-.010759,
.007695,-.010939,
.007,-.011,
-.007,-.011,
-.007695,-.010939,
-.008368,-.010759,
-.009,-.010464,
-.009571,-.010064,
-.010064,-.009571,
-.010464,-.009,
-.010759,-.008368,
-.010939,-.007695,
-.011,-.007,
0.0*
%
%ADD33MACRO33*%
%AMMACRO42*
4,1,40,-.012,-.008,
-.012,.008,
-.011939,.008695,
-.011759,.009368,
-.011464,.01,
-.011064,.010571,
-.010571,.011064,
-.01,.011464,
-.009368,.011759,
-.008695,.011939,
-.008,.012,
.008,.012,
.008695,.011939,
.009368,.011759,
.01,.011464,
.010571,.011064,
.011064,.010571,
.011464,.01,
.011759,.009368,
.011939,.008695,
.012,.008,
.012,-.008,
.011939,-.008695,
.011759,-.009368,
.011464,-.01,
.011064,-.010571,
.010571,-.011064,
.01,-.011464,
.009368,-.011759,
.008695,-.011939,
.008,-.012,
-.008,-.012,
-.008695,-.011939,
-.009368,-.011759,
-.01,-.011464,
-.010571,-.011064,
-.011064,-.010571,
-.011464,-.01,
-.011759,-.009368,
-.011939,-.008695,
-.012,-.008,
0.0*
%
%ADD42MACRO42*%
%AMMACRO73*
4,1,40,-.008,.012,
.008,.012,
.008695,.011939,
.009368,.011759,
.01,.011464,
.010571,.011064,
.011064,.010571,
.011464,.01,
.011759,.009368,
.011939,.008695,
.012,.008,
.012,-.008,
.011939,-.008695,
.011759,-.009368,
.011464,-.01,
.011064,-.010571,
.010571,-.011064,
.01,-.011464,
.009368,-.011759,
.008695,-.011939,
.008,-.012,
-.008,-.012,
-.008695,-.011939,
-.009368,-.011759,
-.01,-.011464,
-.010571,-.011064,
-.011064,-.010571,
-.011464,-.01,
-.011759,-.009368,
-.011939,-.008695,
-.012,-.008,
-.012,.008,
-.011939,.008695,
-.011759,.009368,
-.011464,.01,
-.011064,.010571,
-.010571,.011064,
-.01,.011464,
-.009368,.011759,
-.008695,.011939,
-.008,.012,
0.0*
%
%ADD73MACRO73*%
%AMMACRO27*
4,1,40,-.013,.017,
.013,.017,
.013695,.016939,
.014368,.016759,
.015,.016464,
.015571,.016064,
.016064,.015571,
.016464,.015,
.016759,.014368,
.016939,.013695,
.017,.013,
.017,-.013,
.016939,-.013695,
.016759,-.014368,
.016464,-.015,
.016064,-.015571,
.015571,-.016064,
.015,-.016464,
.014368,-.016759,
.013695,-.016939,
.013,-.017,
-.013,-.017,
-.013695,-.016939,
-.014368,-.016759,
-.015,-.016464,
-.015571,-.016064,
-.016064,-.015571,
-.016464,-.015,
-.016759,-.014368,
-.016939,-.013695,
-.017,-.013,
-.017,.013,
-.016939,.013695,
-.016759,.014368,
-.016464,.015,
-.016064,.015571,
-.015571,.016064,
-.015,.016464,
-.014368,.016759,
-.013695,.016939,
-.013,.017,
0.0*
%
%ADD27MACRO27*%
%AMMACRO67*
4,1,40,.017,.013,
.017,-.013,
.016939,-.013695,
.016759,-.014368,
.016464,-.015,
.016064,-.015571,
.015571,-.016064,
.015,-.016464,
.014368,-.016759,
.013695,-.016939,
.013,-.017,
-.013,-.017,
-.013695,-.016939,
-.014368,-.016759,
-.015,-.016464,
-.015571,-.016064,
-.016064,-.015571,
-.016464,-.015,
-.016759,-.014368,
-.016939,-.013695,
-.017,-.013,
-.017,.013,
-.016939,.013695,
-.016759,.014368,
-.016464,.015,
-.016064,.015571,
-.015571,.016064,
-.015,.016464,
-.014368,.016759,
-.013695,.016939,
-.013,.017,
.013,.017,
.013695,.016939,
.014368,.016759,
.015,.016464,
.015571,.016064,
.016064,.015571,
.016464,.015,
.016759,.014368,
.016939,.013695,
.017,.013,
0.0*
%
%ADD67MACRO67*%
%ADD75R,.06X.012*%
%ADD37R,.13X.128*%
%ADD81R,.128X.13*%
%ADD24R,.044X.012*%
%ADD83R,.012X.044*%
%ADD46C,.111*%
%ADD68R,.128X.105*%
%ADD61R,.012X.036*%
%ADD59R,.036X.012*%
%ADD62R,.012X.037*%
%ADD60R,.037X.012*%
%ADD70R,.065X.05*%
%ADD52C,.404*%
%ADD25R,.045X.055*%
%ADD15R,.055X.045*%
%ADD71R,.047X.073*%
%ADD12C,.256*%
%ADD72R,.09X.095*%
%ADD47R,.095X.09*%
%ADD18C,.375*%
%ADD10C,.296*%
%ADD22O,.552X.788*%
%AMMACRO45*
4,1,40,.012,.008,
.012,-.008,
.011939,-.008695,
.011759,-.009368,
.011464,-.01,
.011064,-.010571,
.010571,-.011064,
.01,-.011464,
.009368,-.011759,
.008695,-.011939,
.008,-.012,
-.008,-.012,
-.008695,-.011939,
-.009368,-.011759,
-.01,-.011464,
-.010571,-.011064,
-.011064,-.010571,
-.011464,-.01,
-.011759,-.009368,
-.011939,-.008695,
-.012,-.008,
-.012,.008,
-.011939,.008695,
-.011759,.009368,
-.011464,.01,
-.011064,.010571,
-.010571,.011064,
-.01,.011464,
-.009368,.011759,
-.008695,.011939,
-.008,.012,
.008,.012,
.008695,.011939,
.009368,.011759,
.01,.011464,
.010571,.011064,
.011064,.010571,
.011464,.01,
.011759,.009368,
.011939,.008695,
.012,.008,
0.0*
%
%ADD45MACRO45*%
%AMMACRO38*
4,1,40,-.007,.011,
.007,.011,
.007695,.010939,
.008368,.010759,
.009,.010464,
.009571,.010064,
.010064,.009571,
.010464,.009,
.010759,.008368,
.010939,.007695,
.011,.007,
.011,-.007,
.010939,-.007695,
.010759,-.008368,
.010464,-.009,
.010064,-.009571,
.009571,-.010064,
.009,-.010464,
.008368,-.010759,
.007695,-.010939,
.007,-.011,
-.007,-.011,
-.007695,-.010939,
-.008368,-.010759,
-.009,-.010464,
-.009571,-.010064,
-.010064,-.009571,
-.010464,-.009,
-.010759,-.008368,
-.010939,-.007695,
-.011,-.007,
-.011,.007,
-.010939,.007695,
-.010759,.008368,
-.010464,.009,
-.010064,.009571,
-.009571,.010064,
-.009,.010464,
-.008368,.010759,
-.007695,.010939,
-.007,.011,
0.0*
%
%ADD38MACRO38*%
%AMMACRO29*
4,1,40,.008,-.012,
-.008,-.012,
-.008695,-.011939,
-.009368,-.011759,
-.01,-.011464,
-.010571,-.011064,
-.011064,-.010571,
-.011464,-.01,
-.011759,-.009368,
-.011939,-.008695,
-.012,-.008,
-.012,.008,
-.011939,.008695,
-.011759,.009368,
-.011464,.01,
-.011064,.010571,
-.010571,.011064,
-.01,.011464,
-.009368,.011759,
-.008695,.011939,
-.008,.012,
.008,.012,
.008695,.011939,
.009368,.011759,
.01,.011464,
.010571,.011064,
.011064,.010571,
.011464,.01,
.011759,.009368,
.011939,.008695,
.012,.008,
.012,-.008,
.011939,-.008695,
.011759,-.009368,
.011464,-.01,
.011064,-.010571,
.010571,-.011064,
.01,-.011464,
.009368,-.011759,
.008695,-.011939,
.008,-.012,
0.0*
%
%ADD29MACRO29*%
%AMMACRO76*
4,1,45,.25591,.11811,
.25591,-.11811,
.252022,-.162547,
.240477,-.205635,
.221625,-.246062,
.19604,-.282603,
.164498,-.314145,
.127958,-.33973,
.08753,-.358582,
.044442,-.370127,
.000005,-.374015,
-.044432,-.370127,
-.08752,-.358582,
-.127947,-.33973,
-.164488,-.314145,
-.19603,-.282603,
-.221615,-.246063,
-.240467,-.205635,
-.252012,-.162547,
-.2559,-.11811,
-.2559,.11811,
-.252012,.162547,
-.240467,.205634,
-.221616,.246061,
-.19603,.282601,
-.164488,.314143,
-.127949,.339728,
-.087521,.35858,
-.044434,.370125,
.000003,.374013,
.04444,.370125,
.087526,.35858,
.127954,.339728,
.16179,.31638,
.165832,.290964,
.174225,.266637,
.186715,.244136,
.202923,.224146,
.222356,.207275,
.24439,.19405,
.248391,.17971,
.251551,.165162,
.25386,.150455,
.25531,.135639,
.255896,.120763,
.25591,.11811,
0.0*
%
%ADD76MACRO76*%
%AMMACRO54*
4,1,40,.011,.007,
.011,-.007,
.010939,-.007695,
.010759,-.008368,
.010464,-.009,
.010064,-.009571,
.009571,-.010064,
.009,-.010464,
.008368,-.010759,
.007695,-.010939,
.007,-.011,
-.007,-.011,
-.007695,-.010939,
-.008368,-.010759,
-.009,-.010464,
-.009571,-.010064,
-.010064,-.009571,
-.010464,-.009,
-.010759,-.008368,
-.010939,-.007695,
-.011,-.007,
-.011,.007,
-.010939,.007695,
-.010759,.008368,
-.010464,.009,
-.010064,.009571,
-.009571,.010064,
-.009,.010464,
-.008368,.010759,
-.007695,.010939,
-.007,.011,
.007,.011,
.007695,.010939,
.008368,.010759,
.009,.010464,
.009571,.010064,
.010064,.009571,
.010464,.009,
.010759,.008368,
.010939,.007695,
.011,.007,
0.0*
%
%ADD54MACRO54*%
%AMMACRO64*
4,1,6,-.0135,-.025,
.0065,-.005,
.0135,-.005,
.0135,.005,
.0065,.005,
-.0135,.025,
-.0135,-.025,
0.0*
%
%ADD64MACRO64*%
%AMMACRO40*
4,1,40,.013,-.017,
-.013,-.017,
-.013695,-.016939,
-.014368,-.016759,
-.015,-.016464,
-.015571,-.016064,
-.016064,-.015571,
-.016464,-.015,
-.016759,-.014368,
-.016939,-.013695,
-.017,-.013,
-.017,.013,
-.016939,.013695,
-.016759,.014368,
-.016464,.015,
-.016064,.015571,
-.015571,.016064,
-.015,.016464,
-.014368,.016759,
-.013695,.016939,
-.013,.017,
.013,.017,
.013695,.016939,
.014368,.016759,
.015,.016464,
.015571,.016064,
.016064,.015571,
.016464,.015,
.016759,.014368,
.016939,.013695,
.017,.013,
.017,-.013,
.016939,-.013695,
.016759,-.014368,
.016464,-.015,
.016064,-.015571,
.015571,-.016064,
.015,-.016464,
.014368,-.016759,
.013695,-.016939,
.013,-.017,
0.0*
%
%ADD40MACRO40*%
%AMMACRO16*
4,1,40,-.017,-.013,
-.017,.013,
-.016939,.013695,
-.016759,.014368,
-.016464,.015,
-.016064,.015571,
-.015571,.016064,
-.015,.016464,
-.014368,.016759,
-.013695,.016939,
-.013,.017,
.013,.017,
.013695,.016939,
.014368,.016759,
.015,.016464,
.015571,.016064,
.016064,.015571,
.016464,.015,
.016759,.014368,
.016939,.013695,
.017,.013,
.017,-.013,
.016939,-.013695,
.016759,-.014368,
.016464,-.015,
.016064,-.015571,
.015571,-.016064,
.015,-.016464,
.014368,-.016759,
.013695,-.016939,
.013,-.017,
-.013,-.017,
-.013695,-.016939,
-.014368,-.016759,
-.015,-.016464,
-.015571,-.016064,
-.016064,-.015571,
-.016464,-.015,
-.016759,-.014368,
-.016939,-.013695,
-.017,-.013,
0.0*
%
%ADD16MACRO16*%
%AMMACRO34*
4,1,6,.005,-.0135,
.005,-.0065,
.025,.0135,
-.025,.0135,
-.005,-.0065,
-.005,-.0135,
.005,-.0135,
0.0*
%
%ADD34MACRO34*%
%AMMACRO82*
4,1,20,-.1075,.0635,
-.1075,.049,
-.118,.049,
-.118,.0395,
-.1075,.0395,
-.1075,-.0395,
-.118,-.0395,
-.118,-.049,
-.1075,-.049,
-.1075,-.0635,
.1075,-.0635,
.1075,-.049,
.118,-.049,
.118,-.0395,
.1075,-.0395,
.1075,.0395,
.118,.0395,
.118,.049,
.1075,.049,
.1075,.0635,
-.1075,.0635,
0.0*
%
%ADD82MACRO82*%
%AMMACRO23*
4,1,20,-.0635,-.1075,
-.049,-.1075,
-.049,-.118,
-.0395,-.118,
-.0395,-.1075,
.0395,-.1075,
.0395,-.118,
.049,-.118,
.049,-.1075,
.0635,-.1075,
.0635,.1075,
.049,.1075,
.049,.118,
.0395,.118,
.0395,.1075,
-.0395,.1075,
-.0395,.118,
-.049,.118,
-.049,.1075,
-.0635,.1075,
-.0635,-.1075,
0.0*
%
%ADD23MACRO23*%
%AMMACRO44*
4,1,40,.012,.008,
.012,-.008,
.011939,-.008695,
.011759,-.009368,
.011464,-.01,
.011064,-.010571,
.010571,-.011064,
.01,-.011464,
.009368,-.011759,
.008695,-.011939,
.008,-.012,
-.008,-.012,
-.008695,-.011939,
-.009368,-.011759,
-.01,-.011464,
-.010571,-.011064,
-.011064,-.010571,
-.011464,-.01,
-.011759,-.009368,
-.011939,-.008695,
-.012,-.008,
-.012,.008,
-.011939,.008695,
-.011759,.009368,
-.011464,.01,
-.011064,.010571,
-.010571,.011064,
-.01,.011464,
-.009368,.011759,
-.008695,.011939,
-.008,.012,
.008,.012,
.008695,.011939,
.009368,.011759,
.01,.011464,
.010571,.011064,
.011064,.010571,
.011464,.01,
.011759,.009368,
.011939,.008695,
.012,.008,
0.0*
%
%ADD44MACRO44*%
%AMMACRO39*
4,1,40,-.007,.011,
.007,.011,
.007695,.010939,
.008368,.010759,
.009,.010464,
.009571,.010064,
.010064,.009571,
.010464,.009,
.010759,.008368,
.010939,.007695,
.011,.007,
.011,-.007,
.010939,-.007695,
.010759,-.008368,
.010464,-.009,
.010064,-.009571,
.009571,-.010064,
.009,-.010464,
.008368,-.010759,
.007695,-.010939,
.007,-.011,
-.007,-.011,
-.007695,-.010939,
-.008368,-.010759,
-.009,-.010464,
-.009571,-.010064,
-.010064,-.009571,
-.010464,-.009,
-.010759,-.008368,
-.010939,-.007695,
-.011,-.007,
-.011,.007,
-.010939,.007695,
-.010759,.008368,
-.010464,.009,
-.010064,.009571,
-.009571,.010064,
-.009,.010464,
-.008368,.010759,
-.007695,.010939,
-.007,.011,
0.0*
%
%ADD39MACRO39*%
%AMMACRO28*
4,1,40,.008,-.012,
-.008,-.012,
-.008695,-.011939,
-.009368,-.011759,
-.01,-.011464,
-.010571,-.011064,
-.011064,-.010571,
-.011464,-.01,
-.011759,-.009368,
-.011939,-.008695,
-.012,-.008,
-.012,.008,
-.011939,.008695,
-.011759,.009368,
-.011464,.01,
-.011064,.010571,
-.010571,.011064,
-.01,.011464,
-.009368,.011759,
-.008695,.011939,
-.008,.012,
.008,.012,
.008695,.011939,
.009368,.011759,
.01,.011464,
.010571,.011064,
.011064,.010571,
.011464,.01,
.011759,.009368,
.011939,.008695,
.012,.008,
.012,-.008,
.011939,-.008695,
.011759,-.009368,
.011464,-.01,
.011064,-.010571,
.010571,-.011064,
.01,-.011464,
.009368,-.011759,
.008695,-.011939,
.008,-.012,
0.0*
%
%ADD28MACRO28*%
%ADD84C,.006*%
G75*
%LPD*%
G75*
G54D10*
X15157Y21653D03*
Y474409D03*
X904921Y-25591D03*
Y564960D03*
X975787Y-25590D03*
X975786Y564960D03*
X1104527Y1630792D03*
X1894685Y21654D03*
X1894684Y474409D03*
G54D20*
X111024Y153681D03*
Y606437D03*
Y1059193D03*
X235236Y153681D03*
Y606437D03*
Y1059193D03*
X359449Y153681D03*
Y606437D03*
Y1059193D03*
X483661Y153681D03*
Y606437D03*
Y1059193D03*
X607874Y153681D03*
Y606437D03*
Y1059193D03*
X732087Y153681D03*
Y606437D03*
Y1059193D03*
X949902Y-115157D03*
X1281693Y153681D03*
Y606437D03*
Y1059193D03*
X1405906Y153681D03*
Y606437D03*
Y1059193D03*
X1530118Y153681D03*
Y606437D03*
Y1059193D03*
X1654331Y153681D03*
Y606437D03*
Y1059193D03*
X1778543Y153681D03*
Y606437D03*
Y1059193D03*
X1902756Y153681D03*
Y606437D03*
Y1059193D03*
G54D11*
G01X363248Y-425196D02*
Y-505196D01*
G01D02*
X1639148D01*
G01X359248Y-409196D02*
G02I-12000J0D01*
G01X354098D02*
G02I-6850J0D01*
G01X347248Y-425196D02*
Y-393196D01*
G01X363248Y-425196D02*
X1639148D01*
G01X363248Y-460696D02*
X1639148D01*
G01X363248Y-409196D02*
X331248D01*
G01X720748Y-425196D02*
Y-505196D01*
G01X858248Y-425196D02*
Y-505196D01*
G01X973248Y-425196D02*
Y-505196D01*
G01X1271648Y-425196D02*
Y-505196D01*
G01X1441648Y-425196D02*
Y-505196D01*
G01X1639148Y-425196D02*
Y-505196D01*
G01X1667148Y-409196D02*
G02I-12000J0D01*
G01X1661998D02*
G02I-6850J0D01*
G01X1655148Y-425196D02*
Y-393196D01*
G01X1671148Y-409196D02*
X1639148D01*
X24508Y5500D03*
X5500Y61492D03*
Y56492D03*
Y51492D03*
Y46492D03*
Y41492D03*
Y66492D03*
Y81492D03*
Y76492D03*
Y96492D03*
Y91492D03*
Y86492D03*
Y71492D03*
Y101492D03*
Y111492D03*
Y116492D03*
Y106492D03*
Y126492D03*
Y121492D03*
Y141492D03*
Y151492D03*
Y161492D03*
Y156492D03*
Y146492D03*
Y131492D03*
Y136492D03*
Y181492D03*
Y191492D03*
Y201492D03*
Y211492D03*
Y171492D03*
Y206492D03*
Y196492D03*
Y176492D03*
Y166492D03*
Y186492D03*
Y231492D03*
Y241492D03*
Y251492D03*
Y261492D03*
Y221492D03*
Y256492D03*
Y246492D03*
Y226492D03*
Y216492D03*
Y236492D03*
Y281492D03*
Y291492D03*
Y301492D03*
Y271492D03*
Y306492D03*
Y296492D03*
Y286492D03*
Y276492D03*
Y266492D03*
Y331492D03*
Y341492D03*
Y351492D03*
Y311492D03*
Y321492D03*
Y356492D03*
Y346492D03*
Y336492D03*
Y326492D03*
Y316492D03*
Y381492D03*
Y391492D03*
Y401492D03*
Y361492D03*
Y371492D03*
Y406492D03*
Y396492D03*
Y386492D03*
Y376492D03*
Y366492D03*
Y451492D03*
Y441492D03*
Y431492D03*
Y421492D03*
Y411492D03*
Y416492D03*
Y436492D03*
Y446492D03*
Y426492D03*
Y501492D03*
Y456492D03*
Y496492D03*
Y531492D03*
Y551492D03*
Y541492D03*
Y521492D03*
Y511492D03*
Y536492D03*
Y546492D03*
Y506492D03*
Y516492D03*
Y526492D03*
Y581492D03*
Y591492D03*
Y571492D03*
Y561492D03*
Y586492D03*
Y596492D03*
Y556492D03*
Y566492D03*
Y576492D03*
Y631492D03*
Y641492D03*
Y621492D03*
Y611492D03*
Y601492D03*
Y636492D03*
Y646492D03*
Y606492D03*
Y616492D03*
Y626492D03*
Y681492D03*
Y691492D03*
Y671492D03*
Y661492D03*
Y651492D03*
Y686492D03*
Y696492D03*
Y656492D03*
Y666492D03*
Y676492D03*
Y731492D03*
Y741492D03*
Y721492D03*
Y711492D03*
Y701492D03*
Y736492D03*
Y706492D03*
Y716492D03*
Y726492D03*
Y781492D03*
Y791492D03*
Y771492D03*
Y761492D03*
Y751492D03*
Y786492D03*
Y746492D03*
Y756492D03*
Y766492D03*
Y776492D03*
Y831492D03*
Y841492D03*
Y821492D03*
Y811492D03*
Y801492D03*
Y836492D03*
Y796492D03*
Y806492D03*
Y816492D03*
Y826492D03*
Y881492D03*
Y871492D03*
Y861492D03*
Y851492D03*
Y886492D03*
Y846492D03*
Y856492D03*
Y866492D03*
Y876492D03*
Y931492D03*
Y921492D03*
Y911492D03*
Y901492D03*
Y891492D03*
Y936492D03*
Y896492D03*
Y906492D03*
Y916492D03*
Y926492D03*
Y976492D03*
Y981492D03*
Y986492D03*
Y966492D03*
Y956492D03*
Y961492D03*
Y971492D03*
Y951492D03*
Y941492D03*
Y946492D03*
Y991492D03*
Y996492D03*
Y1001492D03*
Y1006492D03*
Y1026492D03*
Y1016492D03*
Y1011492D03*
Y1021492D03*
Y1031492D03*
Y1036492D03*
Y1066492D03*
Y1056492D03*
Y1046492D03*
Y1041492D03*
Y1051492D03*
Y1061492D03*
Y1071492D03*
Y1081492D03*
Y1076492D03*
Y1121492D03*
Y1131492D03*
Y1111492D03*
Y1101492D03*
Y1091492D03*
Y1086492D03*
Y1096492D03*
Y1106492D03*
Y1116492D03*
Y1126492D03*
Y1171492D03*
Y1161492D03*
Y1151492D03*
Y1141492D03*
Y1136492D03*
Y1146492D03*
Y1156492D03*
Y1166492D03*
Y1176492D03*
Y1221492D03*
Y1211492D03*
Y1201492D03*
Y1191492D03*
Y1181492D03*
Y1186492D03*
Y1196492D03*
Y1206492D03*
Y1216492D03*
Y1226492D03*
Y1271492D03*
Y1261492D03*
Y1251492D03*
Y1241492D03*
Y1231492D03*
Y1236492D03*
Y1246492D03*
Y1256492D03*
Y1266492D03*
Y1276492D03*
Y1321492D03*
Y1311492D03*
Y1301492D03*
Y1291492D03*
Y1281492D03*
Y1286492D03*
Y1296492D03*
Y1306492D03*
Y1316492D03*
X8983Y1368303D03*
X13983D03*
X18983D03*
X23983D03*
X5500Y1361492D03*
Y1351492D03*
Y1341492D03*
Y1331492D03*
Y1336492D03*
Y1346492D03*
Y1356492D03*
Y1326492D03*
X29508Y5500D03*
X39508D03*
X34508D03*
X44508D03*
X64508D03*
X69508D03*
X54508D03*
X49508D03*
X59508D03*
X28983Y1368303D03*
X33983D03*
X38983D03*
X43983D03*
X48983D03*
X53983D03*
X58983D03*
X63983D03*
X68983D03*
X114508Y5500D03*
X119508D03*
X104508D03*
X94508D03*
X84508D03*
X74508D03*
X79508D03*
X89508D03*
X99508D03*
X109508D03*
X119763Y550725D03*
Y546225D03*
Y555225D03*
X83100Y984800D03*
X78600D03*
X83100Y980300D03*
X78600D03*
Y989300D03*
X83100D03*
X73983Y1368303D03*
X78983D03*
X83983D03*
X88983D03*
X93983D03*
X98983D03*
X107374Y1369303D03*
X112374D03*
X117374D03*
X134508Y5500D03*
X124508D03*
X129508D03*
X169508D03*
X159508D03*
X149508D03*
X139508D03*
X154508D03*
X164508D03*
X144508D03*
X124263Y546225D03*
Y550725D03*
Y555225D03*
X141978Y958572D03*
X142006Y978425D03*
X122374Y1369303D03*
X127374D03*
X132374D03*
X137374D03*
X142374D03*
X147374D03*
X152374D03*
X157374D03*
X162374D03*
X167374D03*
X209508Y5500D03*
X199508D03*
X189508D03*
X179508D03*
X204508D03*
X214508D03*
X174508D03*
X184508D03*
X194508D03*
X209863Y566625D03*
X199102Y969717D03*
Y974717D03*
X183584Y974789D03*
Y969789D03*
X199392Y985113D03*
X183551Y984789D03*
X212063Y976725D03*
X203063D03*
X207563D03*
X216563D03*
X212063Y981725D03*
X216563D03*
X207563D03*
X203063D03*
X199392Y990113D03*
X183551Y989789D03*
X172374Y1369303D03*
X177374D03*
X182374D03*
X187374D03*
X192374D03*
X197374D03*
X202374D03*
X207374D03*
X212374D03*
X217374D03*
X259508Y5500D03*
X249508D03*
X239508D03*
X229508D03*
X219508D03*
X224508D03*
X234508D03*
X244508D03*
X254508D03*
X264508D03*
X250650Y556997D03*
Y561997D03*
X265545Y556794D03*
Y561794D03*
X250661Y572936D03*
Y577936D03*
X265590Y572801D03*
Y577801D03*
X225563Y976725D03*
X221063D03*
X225563Y981725D03*
X221063D03*
X222374Y1369303D03*
X227374D03*
X232374D03*
X237374D03*
X242374D03*
X247374D03*
X252374D03*
X257374D03*
X262374D03*
X309508Y5500D03*
X299508D03*
X289508D03*
X279508D03*
X269508D03*
X304508D03*
X314508D03*
X274508D03*
X284508D03*
X294508D03*
X269763Y569725D03*
X287763D03*
X292263D03*
X274263D03*
X283263D03*
X278763D03*
X283263Y564725D03*
X287763D03*
X292263D03*
X274263D03*
X269763D03*
X278763D03*
X267374Y1369303D03*
X272374D03*
X277374D03*
X282374D03*
X287374D03*
X292374D03*
X297374D03*
X302374D03*
X307374D03*
X312374D03*
X359508Y5500D03*
X349508D03*
X339508D03*
X329508D03*
X319508D03*
X324508D03*
X334508D03*
X344508D03*
X354508D03*
X333983Y1368303D03*
X338983D03*
X343983D03*
X348983D03*
X353983D03*
X358983D03*
X363983D03*
X317374Y1369303D03*
X322374D03*
X327374D03*
X395075Y18639D03*
Y13639D03*
X389508Y5500D03*
X379508D03*
X369508D03*
X364508D03*
X374508D03*
X384508D03*
X394508D03*
X395075Y43639D03*
Y38639D03*
Y33639D03*
Y28639D03*
Y23639D03*
X399000Y62000D03*
X396000Y55500D03*
X396075Y50248D03*
X368983Y1368303D03*
X373983D03*
X378983D03*
X383983D03*
X388983D03*
X393983D03*
X398983D03*
X403983D03*
X408983D03*
X413983D03*
X418983D03*
X423983D03*
X428983D03*
X433983D03*
X438983D03*
X443983D03*
X448983D03*
X453983D03*
X458983D03*
X463983D03*
X468983D03*
X473983D03*
X478983D03*
X483983D03*
X488983D03*
X493983D03*
X498983D03*
X503983D03*
X508983D03*
X517374Y1369303D03*
X522374D03*
X527374D03*
X532374D03*
X537374D03*
X542374D03*
X547374D03*
X552374D03*
X557374D03*
X597051Y7699D03*
Y12699D03*
Y17699D03*
X604146Y5500D03*
X597051Y22699D03*
Y27699D03*
Y32699D03*
Y37699D03*
Y42699D03*
X589000Y64000D03*
X594000Y61500D03*
X596000Y56500D03*
X596051Y51090D03*
X567374Y1369303D03*
X572374D03*
X577374D03*
X582374D03*
X587374D03*
X592374D03*
X597374D03*
X602374D03*
X562374D03*
X609146Y5500D03*
X619146D03*
X614146D03*
X629146D03*
X639146D03*
X649146D03*
X654146D03*
X644146D03*
X634146D03*
X624146D03*
X637592Y593186D03*
X641792D03*
Y597386D03*
X637592D03*
X633392Y593186D03*
Y597386D03*
X629192Y593186D03*
Y597386D03*
X641792Y605786D03*
Y601586D03*
X637592D03*
Y605786D03*
X633392D03*
Y601586D03*
X629192D03*
Y605786D03*
X617374Y1369303D03*
X622374D03*
X627374D03*
X632374D03*
X637374D03*
X642374D03*
X647374D03*
X652374D03*
X607374D03*
X612374D03*
X679146Y5500D03*
X689146D03*
X694146D03*
X684146D03*
X659146D03*
X669146D03*
X664146D03*
X674146D03*
X699146D03*
X675913Y586555D03*
Y592955D03*
Y598155D03*
X672082Y582834D03*
X666882D03*
X661682D03*
X656482D03*
X695413Y600755D03*
X699613D03*
X669482Y613934D03*
Y609734D03*
X665282D03*
Y613934D03*
X661082D03*
Y609734D03*
X656882Y613934D03*
Y609734D03*
X675913Y603355D03*
X695413Y604955D03*
X691213Y613355D03*
X695413D03*
X699613D03*
X691213Y609155D03*
X695413D03*
X699613Y604955D03*
Y609155D03*
X702483Y945989D03*
X667374Y1369303D03*
X672374D03*
X677374D03*
X682374D03*
X687374D03*
X692374D03*
X697374D03*
X702374D03*
X657374D03*
X662374D03*
X749146Y5500D03*
X709146D03*
X719146D03*
X729146D03*
X739146D03*
X744146D03*
X734146D03*
X724146D03*
X714146D03*
X704146D03*
X703813Y592355D03*
Y596555D03*
Y600755D03*
X704399Y626799D03*
Y618399D03*
Y622599D03*
X703813Y613355D03*
Y609155D03*
Y604955D03*
X721552Y951317D03*
X725852Y951067D03*
X747374Y1369303D03*
X742374D03*
X717374D03*
X722374D03*
X727374D03*
X732374D03*
X737374D03*
X707374D03*
X712374D03*
X795969Y-1374D03*
X759146Y5500D03*
X769146D03*
X774146D03*
X764146D03*
X754146D03*
X779146D03*
X755500Y1374500D03*
X752500Y1370500D03*
X757287Y1380873D03*
Y1385873D03*
Y1390873D03*
Y1395873D03*
Y1400873D03*
Y1405873D03*
Y1410873D03*
Y1415873D03*
Y1420873D03*
Y1425873D03*
Y1430873D03*
Y1435873D03*
Y1440873D03*
Y1445873D03*
X766156Y1462004D03*
X771156D03*
X790500Y1466500D03*
X786000Y1463500D03*
X756287Y1459264D03*
Y1454264D03*
X779547Y1463004D03*
X792902Y1477964D03*
Y1487964D03*
Y1497964D03*
Y1507964D03*
Y1517964D03*
Y1512964D03*
Y1472964D03*
Y1482964D03*
Y1492964D03*
Y1502964D03*
Y1562964D03*
Y1527964D03*
Y1537964D03*
Y1547964D03*
Y1557964D03*
Y1567964D03*
Y1522964D03*
Y1532964D03*
Y1542964D03*
Y1552964D03*
Y1612964D03*
Y1602964D03*
Y1592964D03*
Y1582964D03*
Y1572964D03*
Y1577964D03*
Y1587964D03*
Y1597964D03*
Y1607964D03*
X797902Y1652964D03*
X792902D03*
Y1642964D03*
Y1632964D03*
Y1622964D03*
Y1627964D03*
Y1637964D03*
Y1647964D03*
Y1617964D03*
X872642Y-140575D03*
Y-135575D03*
Y-130575D03*
Y-125575D03*
X890264Y-147256D03*
X880264D03*
X875264D03*
X885264D03*
X895264D03*
X872642Y-80575D03*
Y-120575D03*
Y-115575D03*
Y-110575D03*
Y-105575D03*
Y-100575D03*
Y-95575D03*
Y-90575D03*
Y-85575D03*
Y-30575D03*
Y-35575D03*
Y-40575D03*
Y-45575D03*
Y-50575D03*
Y-55575D03*
Y-60575D03*
Y-65575D03*
Y-70575D03*
Y-75575D03*
Y-20575D03*
Y-25575D03*
X940264Y-147256D03*
X930264D03*
X925264D03*
X935264D03*
X920264D03*
X910264D03*
X900264D03*
X905264D03*
X915264D03*
X960264D03*
X950264D03*
X955264D03*
X965264D03*
X945264D03*
X990264D03*
X980264D03*
X970264D03*
X975264D03*
X985264D03*
X1010264D03*
X1000264D03*
X1005264D03*
X1015264D03*
X995264D03*
X1040264D03*
X1030264D03*
X1020264D03*
X1025264D03*
X1035264D03*
X1060264D03*
X1050264D03*
X1055264D03*
X1065264D03*
X1045264D03*
X1080264D03*
X1070264D03*
X1075264D03*
X1085264D03*
X1078098Y1652768D03*
X1073098D03*
X1083098D03*
X1088098D03*
X1110264Y-147256D03*
X1100264D03*
X1090264D03*
X1105264D03*
X1095264D03*
X1130264D03*
X1120264D03*
X1115264D03*
X1125264D03*
X1135264D03*
X1093098Y1652768D03*
X1133098D03*
X1123098D03*
X1113098D03*
X1103098D03*
X1108098D03*
X1118098D03*
X1128098D03*
X1098098D03*
X1170264Y-147256D03*
X1155264D03*
X1175602Y-137594D03*
Y-127594D03*
X1160264Y-147256D03*
X1150264D03*
X1140264D03*
X1145264D03*
X1175602Y-132594D03*
Y-142594D03*
X1165264Y-147256D03*
X1175602Y-117594D03*
Y-107594D03*
Y-97594D03*
Y-87594D03*
Y-77594D03*
Y-82594D03*
Y-92594D03*
Y-102594D03*
Y-112594D03*
Y-122594D03*
Y-67594D03*
Y-57594D03*
Y-47594D03*
Y-37594D03*
Y-32594D03*
Y-42594D03*
Y-52594D03*
Y-62594D03*
Y-72594D03*
Y-17594D03*
Y-27594D03*
X1180500Y4000D03*
X1176500Y-500D03*
X1175602Y-22594D03*
Y-12594D03*
Y-7594D03*
X1162000Y1371500D03*
X1169783Y1369303D03*
X1179783D03*
X1174783D03*
X1184783D03*
X1158673Y1417067D03*
Y1407067D03*
Y1397067D03*
Y1387067D03*
Y1377067D03*
Y1412067D03*
Y1402067D03*
Y1392067D03*
Y1382067D03*
Y1422067D03*
Y1442067D03*
Y1452067D03*
X1158500Y1468500D03*
X1158673Y1457067D03*
Y1447067D03*
Y1437067D03*
Y1427067D03*
Y1462067D03*
Y1432067D03*
X1161000Y1474500D03*
X1166673Y1477941D03*
X1171673D03*
X1181673D03*
X1176673D03*
X1143098Y1652768D03*
X1183098D03*
X1173098D03*
X1163098D03*
X1153098D03*
X1158098D03*
X1168098D03*
X1178098D03*
X1138098D03*
X1148098D03*
X1191382Y5500D03*
X1196382D03*
X1186382D03*
X1201382D03*
X1211382D03*
X1221382D03*
X1231382D03*
X1226382D03*
X1216382D03*
X1206382D03*
X1199783Y1369303D03*
X1209783D03*
X1219783D03*
X1229783D03*
X1189783D03*
X1224783D03*
X1214783D03*
X1204783D03*
X1194783D03*
X1191673Y1477941D03*
X1201673D03*
X1214972Y1482642D03*
Y1517642D03*
Y1487642D03*
Y1497642D03*
Y1507642D03*
Y1512642D03*
Y1502642D03*
Y1492642D03*
X1206673Y1477941D03*
X1196673D03*
X1186673D03*
X1211673D03*
X1214972Y1567642D03*
Y1527642D03*
Y1537642D03*
Y1547642D03*
Y1557642D03*
Y1562642D03*
Y1552642D03*
Y1542642D03*
Y1532642D03*
Y1522642D03*
Y1577642D03*
Y1587642D03*
Y1597642D03*
Y1607642D03*
Y1612642D03*
Y1602642D03*
Y1592642D03*
Y1582642D03*
Y1572642D03*
Y1617642D03*
Y1627642D03*
Y1637642D03*
X1213098Y1652768D03*
X1193098D03*
X1203098D03*
X1208098D03*
X1214972Y1642642D03*
Y1632642D03*
X1188098Y1652768D03*
X1198098D03*
X1214972Y1622642D03*
Y1647642D03*
X1251382Y5500D03*
X1261382D03*
X1271382D03*
X1281382D03*
X1276382D03*
X1266382D03*
X1256382D03*
X1241382D03*
X1246382D03*
X1236382D03*
X1249783Y1369303D03*
X1259783D03*
X1269783D03*
X1279783D03*
X1239783D03*
X1274783D03*
X1264783D03*
X1254783D03*
X1234783D03*
X1244783D03*
X1301382Y5500D03*
X1311382D03*
X1296382D03*
X1316382D03*
X1306382D03*
X1291382D03*
X1286382D03*
X1326382D03*
X1321382D03*
X1299783Y1369303D03*
X1309783D03*
X1319783D03*
X1329783D03*
X1289783D03*
X1324783D03*
X1314783D03*
X1304783D03*
X1294783D03*
X1284783D03*
X1363579Y19821D03*
Y14821D03*
Y9821D03*
X1351382Y5500D03*
X1356382D03*
X1346382D03*
X1336382D03*
X1341382D03*
X1331382D03*
X1363579Y44821D03*
Y39821D03*
Y34821D03*
Y29821D03*
Y24821D03*
X1374000Y64500D03*
X1363579Y51618D03*
X1370200Y550500D03*
X1366000D03*
X1378100Y530200D03*
Y534400D03*
X1365500Y538600D03*
X1369700D03*
X1365500Y534400D03*
X1369700D03*
X1373900D03*
X1365500Y530200D03*
X1369700D03*
X1373900D03*
X1375900Y568500D03*
X1366000Y563100D03*
X1370200D03*
Y554700D03*
X1366000D03*
X1370200Y558900D03*
X1366000D03*
X1373700Y582900D03*
X1369500D03*
X1377900Y587100D03*
Y591300D03*
Y595500D03*
X1373700D03*
Y591300D03*
Y587100D03*
X1369500Y595500D03*
Y591300D03*
Y587100D03*
X1377900Y599700D03*
X1373700D03*
X1369500D03*
X1349783Y1369303D03*
X1359783D03*
X1369783D03*
X1339783D03*
X1374783D03*
X1364783D03*
X1354783D03*
X1344783D03*
X1334783D03*
X1396500Y549500D03*
X1386500Y534400D03*
Y530200D03*
X1382300D03*
Y534400D03*
X1396500Y559900D03*
Y554700D03*
Y565100D03*
X1393000Y568500D03*
X1387300D03*
X1381600D03*
X1382100Y587100D03*
X1386300D03*
X1399783Y1369303D03*
X1409783D03*
X1419783D03*
X1379783D03*
X1389783D03*
X1404783D03*
X1414783D03*
X1424783D03*
X1394783D03*
X1384783D03*
X1434441Y590424D03*
X1434581Y586136D03*
X1449783Y1369303D03*
X1459783D03*
X1469783D03*
X1429783D03*
X1439783D03*
X1444783D03*
X1454783D03*
X1464783D03*
X1474783D03*
X1434783D03*
X1499783D03*
X1509783D03*
X1519783D03*
X1479783D03*
X1489783D03*
X1494783D03*
X1484783D03*
X1504783D03*
X1514783D03*
X1565555Y16517D03*
X1568030Y5500D03*
X1565555Y21517D03*
Y26517D03*
Y31517D03*
Y36517D03*
Y41517D03*
X1557000Y64500D03*
X1561500Y62000D03*
X1564000Y57500D03*
X1564555Y52124D03*
X1549783Y1369303D03*
X1559783D03*
X1569783D03*
X1529783D03*
X1539783D03*
X1524783D03*
X1534783D03*
X1544783D03*
X1554783D03*
X1564783D03*
X1603030Y5500D03*
X1613030D03*
X1573030D03*
X1583030D03*
X1593030D03*
X1618030D03*
X1608030D03*
X1598030D03*
X1588030D03*
X1578030D03*
X1614783Y1369303D03*
X1604783D03*
X1599783D03*
X1609783D03*
X1619783D03*
X1579783D03*
X1589783D03*
X1574783D03*
X1584783D03*
X1594783D03*
X1653030Y5500D03*
X1663030D03*
X1623030D03*
X1633030D03*
X1643030D03*
X1668030D03*
X1658030D03*
X1648030D03*
X1638030D03*
X1628030D03*
X1664783Y1369303D03*
X1654783D03*
X1644783D03*
X1634783D03*
X1624783D03*
X1649783D03*
X1659783D03*
X1629783D03*
X1639783D03*
X1703030Y5500D03*
X1713030D03*
X1673030D03*
X1683030D03*
X1693030D03*
X1718030D03*
X1708030D03*
X1698030D03*
X1688030D03*
X1678030D03*
X1697261Y1004347D03*
X1692761D03*
Y999847D03*
Y995347D03*
X1697261D03*
Y999847D03*
X1714783Y1369303D03*
X1704783D03*
X1694783D03*
X1684783D03*
X1674783D03*
X1699783D03*
X1709783D03*
X1669783D03*
X1679783D03*
X1689783D03*
X1753030Y5500D03*
X1763030D03*
X1723030D03*
X1733030D03*
X1743030D03*
X1758030D03*
X1748030D03*
X1738030D03*
X1728030D03*
X1764783Y1369303D03*
X1754783D03*
X1744783D03*
X1734783D03*
X1724783D03*
X1749783D03*
X1759783D03*
X1719783D03*
X1729783D03*
X1739783D03*
X1778030Y5500D03*
X1793030D03*
X1803030D03*
X1813030D03*
X1808030D03*
X1798030D03*
X1783030D03*
X1788030D03*
X1773030D03*
X1768030D03*
X1783806Y989468D03*
X1804783Y1369303D03*
X1794783D03*
X1784783D03*
X1774783D03*
X1799783D03*
X1809783D03*
X1769783D03*
X1779783D03*
X1789783D03*
X1843030Y5500D03*
X1853030D03*
X1863030D03*
X1838030D03*
X1858030D03*
X1848030D03*
X1823030D03*
X1833030D03*
X1828030D03*
X1818030D03*
X1862652Y846508D03*
X1850263Y964540D03*
X1850370Y960239D03*
X1845870D03*
X1845763Y964540D03*
Y956040D03*
X1850263D03*
X1825741Y969210D03*
Y974210D03*
X1840683Y969318D03*
Y974318D03*
X1825744Y986011D03*
X1840578Y985885D03*
X1844863Y983125D03*
X1853863D03*
X1858363D03*
X1849363D03*
X1862863D03*
X1853863Y978125D03*
X1844863D03*
X1849363D03*
X1862863D03*
X1858363D03*
X1825744Y991011D03*
X1840578Y990885D03*
X1854783Y1369303D03*
X1844783D03*
X1834783D03*
X1824783D03*
X1814783D03*
X1849783D03*
X1859783D03*
X1819783D03*
X1829783D03*
X1839783D03*
X1878030Y5500D03*
X1883030D03*
X1873030D03*
X1868030D03*
X1909030D03*
X1888030D03*
X1873099Y817150D03*
X1878099D03*
X1873099Y821650D03*
X1878099D03*
X1873099Y826150D03*
X1878099D03*
X1877512Y831377D03*
X1882512D03*
X1865202Y831559D03*
X1873012Y831377D03*
X1878099Y812650D03*
X1873099D03*
X1878099Y808150D03*
X1873099D03*
X1878099Y803650D03*
X1873099D03*
X1878373Y846472D03*
X1883373D03*
X1867652Y846508D03*
X1867363Y983125D03*
Y978125D03*
X1904783Y1369303D03*
X1894783D03*
X1884783D03*
X1874783D03*
X1864783D03*
X1899783D03*
X1909783D03*
X1869783D03*
X1879783D03*
X1889783D03*
X1929343Y16525D03*
Y11525D03*
Y6525D03*
X1914030Y5500D03*
X1919030D03*
X1924030D03*
X1929343Y46525D03*
Y41525D03*
Y36525D03*
Y31525D03*
Y26525D03*
Y21525D03*
Y66525D03*
Y61525D03*
Y56525D03*
Y51525D03*
Y116525D03*
Y111525D03*
Y106525D03*
Y101525D03*
Y96525D03*
Y91525D03*
Y86525D03*
Y81525D03*
Y76525D03*
Y71525D03*
Y121525D03*
Y126525D03*
Y136525D03*
Y146525D03*
Y156525D03*
Y161525D03*
Y151525D03*
Y141525D03*
Y131525D03*
Y176525D03*
Y186525D03*
Y196525D03*
Y206525D03*
Y166525D03*
Y211525D03*
Y201525D03*
Y191525D03*
Y181525D03*
Y171525D03*
Y226525D03*
Y236525D03*
Y246525D03*
Y256525D03*
Y216525D03*
Y261525D03*
Y251525D03*
Y241525D03*
Y231525D03*
Y221525D03*
Y276525D03*
Y286525D03*
Y296525D03*
Y306525D03*
Y266525D03*
Y301525D03*
Y291525D03*
Y281525D03*
Y271525D03*
Y326525D03*
Y336525D03*
Y346525D03*
Y356525D03*
Y316525D03*
Y351525D03*
Y341525D03*
Y331525D03*
Y321525D03*
Y311525D03*
Y376525D03*
Y386525D03*
Y396525D03*
Y406525D03*
Y366525D03*
Y401525D03*
Y391525D03*
Y381525D03*
Y371525D03*
Y361525D03*
Y426525D03*
Y436525D03*
Y446525D03*
Y416525D03*
Y451525D03*
Y441525D03*
Y431525D03*
Y421525D03*
Y411525D03*
Y476525D03*
Y486525D03*
Y496525D03*
Y456525D03*
Y466525D03*
Y501525D03*
Y491525D03*
Y481525D03*
Y471525D03*
Y461525D03*
Y526525D03*
Y536525D03*
Y546525D03*
Y506525D03*
Y516525D03*
Y551525D03*
Y541525D03*
Y531525D03*
Y521525D03*
Y511525D03*
Y576525D03*
Y586525D03*
Y596525D03*
Y556525D03*
Y566525D03*
Y591525D03*
Y581525D03*
Y571525D03*
Y561525D03*
Y626525D03*
Y636525D03*
Y646525D03*
Y606525D03*
Y616525D03*
Y641525D03*
Y631525D03*
Y621525D03*
Y611525D03*
Y601525D03*
Y676525D03*
Y686525D03*
Y696525D03*
Y656525D03*
Y666525D03*
Y691525D03*
Y681525D03*
Y671525D03*
Y661525D03*
Y651525D03*
Y726525D03*
Y736525D03*
Y706525D03*
Y716525D03*
Y741525D03*
Y731525D03*
Y721525D03*
Y711525D03*
Y701525D03*
Y776525D03*
Y786525D03*
Y746525D03*
Y756525D03*
Y766525D03*
Y791525D03*
Y781525D03*
Y771525D03*
Y761525D03*
Y751525D03*
Y826525D03*
Y836525D03*
Y796525D03*
Y806525D03*
Y816525D03*
Y841525D03*
Y831525D03*
Y821525D03*
Y811525D03*
Y801525D03*
Y876525D03*
Y886525D03*
Y846525D03*
Y856525D03*
Y866525D03*
Y881525D03*
Y871525D03*
Y861525D03*
Y851525D03*
Y926525D03*
Y896525D03*
Y906525D03*
Y916525D03*
Y931525D03*
Y921525D03*
Y911525D03*
Y901525D03*
Y891525D03*
Y936525D03*
Y973863D03*
Y978863D03*
Y983863D03*
Y951525D03*
Y956525D03*
Y961525D03*
Y966525D03*
Y946525D03*
Y941525D03*
Y988863D03*
Y993863D03*
Y998863D03*
Y1003863D03*
Y1008863D03*
Y1033863D03*
Y1028863D03*
Y1023863D03*
Y1018863D03*
Y1013863D03*
Y1073863D03*
Y1083863D03*
Y1043863D03*
Y1053863D03*
Y1063863D03*
Y1078863D03*
Y1068863D03*
Y1058863D03*
Y1048863D03*
Y1038863D03*
Y1123863D03*
Y1093863D03*
Y1103863D03*
Y1113863D03*
Y1128863D03*
Y1118863D03*
Y1108863D03*
Y1098863D03*
Y1088863D03*
Y1173863D03*
Y1133863D03*
Y1143863D03*
Y1153863D03*
Y1163863D03*
Y1178863D03*
Y1168863D03*
Y1158863D03*
Y1148863D03*
Y1138863D03*
Y1223863D03*
Y1183863D03*
Y1193863D03*
Y1203863D03*
Y1213863D03*
Y1228863D03*
Y1218863D03*
Y1208863D03*
Y1198863D03*
Y1188863D03*
Y1273863D03*
Y1233863D03*
Y1243863D03*
Y1253863D03*
Y1263863D03*
Y1268863D03*
Y1258863D03*
Y1248863D03*
Y1238863D03*
Y1323863D03*
Y1283863D03*
Y1293863D03*
Y1303863D03*
Y1313863D03*
Y1318863D03*
Y1308863D03*
Y1298863D03*
Y1288863D03*
Y1278863D03*
Y1333863D03*
Y1343863D03*
Y1353863D03*
X1924783Y1369303D03*
X1914783D03*
X1919783D03*
X1929343Y1358863D03*
Y1348863D03*
Y1338863D03*
Y1328863D03*
Y1363863D03*
G54D12*
X31496Y882677D03*
X168307Y646457D03*
X660236D03*
X718110Y820866D03*
X1366142Y646457D03*
X1462992Y866929D03*
X1602756Y646457D03*
X1903346Y803937D03*
G54D21*
X111024Y302303D03*
Y755059D03*
Y1207815D03*
X235236Y302303D03*
Y755059D03*
Y1207815D03*
X359449Y302303D03*
Y755059D03*
Y1207815D03*
X483661Y302303D03*
Y755059D03*
Y1207815D03*
X607874Y302303D03*
Y755059D03*
Y1207815D03*
X732087Y302303D03*
Y755059D03*
Y1207815D03*
X1098524Y-115157D03*
X1281693Y302303D03*
Y755059D03*
Y1207815D03*
X1405906Y302303D03*
Y755059D03*
Y1207815D03*
X1530118Y302303D03*
Y755059D03*
Y1207815D03*
X1654331Y302303D03*
Y755059D03*
Y1207815D03*
X1778543Y302303D03*
Y755059D03*
Y1207815D03*
X1902756Y302303D03*
Y755059D03*
Y1207815D03*
G54D30*
X111800Y987200D03*
Y983200D03*
X115800Y979200D03*
X119800Y971200D03*
Y975200D03*
Y979200D03*
X115800Y975200D03*
X119800Y987200D03*
Y983200D03*
X115800Y971200D03*
Y983200D03*
Y987200D03*
X182500Y559200D03*
Y571200D03*
Y575200D03*
X178500D03*
Y571200D03*
X182500Y567200D03*
X186500Y559200D03*
Y563200D03*
Y567200D03*
X182500Y563200D03*
X186500Y575200D03*
Y571200D03*
X730882Y888502D03*
X1757600Y987200D03*
X1761600D03*
Y983200D03*
X1757600D03*
X1761600Y991200D03*
Y999200D03*
Y995200D03*
X1757600Y991200D03*
X1753600Y995200D03*
Y999200D03*
X1757600D03*
Y995200D03*
X1860276Y916059D03*
Y912059D03*
X1872276Y916059D03*
X1876276D03*
Y920059D03*
X1872276D03*
X1868276Y916059D03*
X1864276Y912059D03*
X1868276D03*
X1864276Y916059D03*
X1876276Y912059D03*
X1872276D03*
G54D40*
X135026Y997741D03*
X201726Y585741D03*
X754304Y864973D03*
X1776826Y1009741D03*
X1902159Y905750D03*
G54D22*
X131201Y377154D03*
X131200Y829910D03*
X131201Y1282666D03*
X379232Y377154D03*
Y829910D03*
Y1282666D03*
X627263Y377154D03*
Y829910D03*
Y1282666D03*
X796457Y263003D03*
Y735444D03*
X961418Y1087413D03*
Y1429932D03*
X1181890Y555917D03*
X1181870Y969280D03*
X1181890Y1559854D03*
X1301870Y377154D03*
Y829910D03*
Y1282666D03*
X1549901Y377154D03*
Y829910D03*
Y1282666D03*
X1797933Y377154D03*
Y829910D03*
Y1282666D03*
G54D13*
X35506Y-110687D03*
X63128Y89671D03*
X60754Y1316385D03*
X72380Y1596505D03*
X1861177Y91072D03*
X1874818Y-110232D03*
G54D31*
X101403Y981195D03*
X168103Y569195D03*
X137163Y987125D03*
X145363Y997741D03*
X212063Y585741D03*
X203863Y575125D03*
X737984Y861689D03*
X747383Y924689D03*
X753893Y912630D03*
X779535Y1180469D03*
X792263Y1178661D03*
Y1174461D03*
Y1170261D03*
X784544Y1210178D03*
Y1205978D03*
X779535Y1193469D03*
Y1189269D03*
Y1184669D03*
X797177Y1189537D03*
X797225Y1185337D03*
X792263Y1182861D03*
X1737241Y997843D03*
X1787163Y1009741D03*
X1778963Y999125D03*
G54D23*
X115800Y979200D03*
X182500Y567200D03*
X1757600Y991200D03*
G54D32*
X119741Y999116D03*
X151536Y997374D03*
X218236Y585374D03*
X186441Y587116D03*
X737984Y868796D03*
X852500Y487900D03*
X861900Y487800D03*
X1761541Y1011116D03*
X1793336Y1009374D03*
X1906500Y890200D03*
X1896943Y900950D03*
X1905943D03*
X1892500Y890700D03*
X1884500Y909200D03*
G54D14*
X60540Y-85109D03*
X59536Y1573374D03*
X79000Y1301900D03*
X1826700Y77600D03*
X1865705Y1573374D03*
X1898432Y-93682D03*
X1908500Y1346800D03*
G54D50*
X496653Y80906D03*
X1465157D03*
G54D41*
X140626Y997741D03*
X207326Y585741D03*
X759904Y864973D03*
X1782426Y1009741D03*
X1907759Y905750D03*
G54D15*
X63500Y975500D03*
Y967900D03*
X71500Y967800D03*
Y975400D03*
X79300Y967800D03*
Y975400D03*
X87100Y967800D03*
Y975400D03*
X138200Y555800D03*
Y563400D03*
X146000Y555800D03*
Y563400D03*
X153800Y555800D03*
Y563400D03*
X205400Y989100D03*
Y996700D03*
X213200Y989100D03*
Y996700D03*
X221000Y989100D03*
Y996700D03*
X272100Y577100D03*
Y584700D03*
X279900Y577100D03*
Y584700D03*
X287700Y577100D03*
Y584700D03*
X701782Y929902D03*
Y922302D03*
X712898Y938082D03*
X720798D03*
X728698D03*
X712898Y945682D03*
X720798D03*
X728698D03*
X764418Y895398D03*
Y902998D03*
X756618Y895398D03*
Y902998D03*
X1703183Y996313D03*
Y988713D03*
X1711618Y988629D03*
Y996229D03*
X1719418Y988629D03*
Y996229D03*
X1727218Y988629D03*
Y996229D03*
X1847200Y990500D03*
Y998100D03*
X1855000Y990500D03*
Y998100D03*
X1862800Y990500D03*
Y998100D03*
X1882801Y937996D03*
Y945596D03*
G54D60*
X736938Y887518D03*
Y889486D03*
X724826D03*
Y887518D03*
G54D24*
X106157Y985106D03*
Y983137D03*
Y981169D03*
Y979200D03*
Y977231D03*
Y975263D03*
Y973294D03*
Y971326D03*
Y969357D03*
Y989043D03*
Y987074D03*
X125443Y969357D03*
Y971326D03*
Y973294D03*
Y975263D03*
Y977231D03*
Y979200D03*
Y981169D03*
Y983137D03*
Y985106D03*
Y987074D03*
Y989043D03*
X172857Y577043D03*
Y575074D03*
Y573106D03*
Y571137D03*
Y569169D03*
Y567200D03*
Y565231D03*
Y563263D03*
Y561294D03*
Y559326D03*
Y557357D03*
X192143D03*
Y559326D03*
Y561294D03*
Y563263D03*
Y565231D03*
Y567200D03*
Y569169D03*
Y571137D03*
Y573106D03*
Y575074D03*
Y577043D03*
X1747957Y985294D03*
Y983326D03*
Y981357D03*
Y1001043D03*
Y999074D03*
Y997106D03*
Y995137D03*
Y993169D03*
Y991200D03*
Y989231D03*
Y987263D03*
X1767243Y981357D03*
Y983326D03*
Y985294D03*
Y987263D03*
Y989231D03*
Y991200D03*
Y993169D03*
Y995137D03*
Y997106D03*
Y999074D03*
Y1001043D03*
G54D42*
X125263Y1001725D03*
X191963Y589725D03*
X1767063Y1013725D03*
X1847200Y904000D03*
X1864700Y936500D03*
G54D33*
X119741Y995716D03*
X151536Y993974D03*
X218236Y581974D03*
X186441Y583716D03*
X737984Y865396D03*
X852500Y484500D03*
X861900Y484400D03*
X1761541Y1007716D03*
X1793336Y1005974D03*
X1892500Y887300D03*
X1906500Y886800D03*
X1896943Y897550D03*
X1905943D03*
X1884500Y905800D03*
G54D51*
X496653Y110552D03*
X1465157D03*
G54D34*
X114000Y998550D03*
X180700Y586550D03*
X1755800Y1010550D03*
G54D16*
X63463Y987125D03*
X129763Y560525D03*
X156941Y998444D03*
X223641Y586444D03*
X1702761Y1009647D03*
X1798741Y1010444D03*
G54D25*
X95363Y987725D03*
X87763D03*
X129700Y548400D03*
X137300D03*
X162063Y575725D03*
X154463D03*
X741782Y938102D03*
X749382D03*
X741782Y930302D03*
X749382D03*
X741782Y946002D03*
X749382D03*
X863032Y396400D03*
X870632D03*
X1057358Y394574D03*
X1064958D03*
X1735481Y1008554D03*
X1727881D03*
X1861617Y808535D03*
X1854017D03*
X1861617Y816335D03*
X1854017D03*
X1861617Y824135D03*
X1854017D03*
X1850800Y918500D03*
X1843200D03*
X1855800Y934500D03*
X1848200D03*
X1855200Y958500D03*
X1862800D03*
X1855800Y942500D03*
X1848200D03*
X1862700D03*
Y950500D03*
X1855800D03*
X1848200D03*
X1870300Y942500D03*
Y950500D03*
G54D52*
X503248Y829921D03*
X1673917D03*
G54D70*
X763818Y888398D03*
Y877398D03*
G54D61*
X727929Y882396D03*
X733835D03*
Y894608D03*
X727929D03*
G54D43*
X128863Y1001725D03*
X195563Y589725D03*
X1770663Y1013725D03*
X1850800Y904000D03*
X1868300Y936500D03*
G54D44*
X154856Y1002801D03*
X221556Y590801D03*
X749461Y868854D03*
X726225Y873544D03*
X1796656Y1014801D03*
X1850800Y907500D03*
G54D71*
X872366Y406550D03*
X861398D03*
X1066784Y404700D03*
X1055816D03*
G54D62*
X729898Y882446D03*
X731866D03*
Y894558D03*
X729898D03*
G54D35*
X114000Y996050D03*
X180700Y584050D03*
X1755800Y1008050D03*
G54D26*
X96393Y981195D03*
X163093Y569195D03*
X751983Y920289D03*
X1736511Y1002024D03*
X1835866Y907899D03*
X1861800Y965000D03*
X1887520Y874918D03*
G54D53*
X694613Y593113D03*
Y621397D03*
G54D80*
X1358858Y596400D03*
X1387142D03*
G54D17*
X63463Y981525D03*
X129763Y554925D03*
X156941Y992844D03*
X223641Y580844D03*
X1702761Y1004047D03*
X1798741Y1004844D03*
G54D54*
X711711Y881500D03*
X743200Y874600D03*
X729182Y862502D03*
X874900Y471600D03*
X872000Y484300D03*
X856900Y484500D03*
X866100Y484400D03*
X1888000Y887300D03*
X1889500Y905800D03*
X1892443Y897550D03*
G54D45*
X151256Y1002801D03*
X217956Y590801D03*
X745861Y868854D03*
X722625Y873544D03*
X1793056Y1014801D03*
X1847200Y907500D03*
G54D18*
X103642Y36220D03*
X173228Y1062992D03*
X421653Y1141732D03*
X654822Y36220D03*
X670079Y1062992D03*
X1274311Y36220D03*
X1343701Y1062992D03*
X1592126Y1141732D03*
X1825492Y36220D03*
X1840551Y1062992D03*
G54D72*
X854849Y423076D03*
X879649D03*
X1041380Y421129D03*
X1066180D03*
X1841693Y839032D03*
X1905593D03*
X1880793D03*
X1866493D03*
G54D81*
X1857176Y858948D03*
Y893570D03*
G54D27*
X90793Y981195D03*
X157493Y569195D03*
X746383Y920289D03*
X1730911Y1002024D03*
X1830266Y907899D03*
X1856200Y965000D03*
X1881920Y874918D03*
G54D63*
X722319Y865905D03*
X1887626Y917859D03*
G54D36*
X79563Y994472D03*
X140385Y572680D03*
X146263Y582472D03*
X126711Y959847D03*
X156063Y1007725D03*
X142563Y1006625D03*
X134063Y1003225D03*
X209163Y594425D03*
X200763Y591225D03*
X222763Y595725D03*
X223100Y920600D03*
X289510Y1342259D03*
X447533Y475900D03*
X458679Y470700D03*
X429613Y1017920D03*
X432657Y1015102D03*
X422373Y1359747D03*
X418922Y1356522D03*
X462133Y473300D03*
X481533Y480875D03*
X536000Y1359826D03*
X541362D03*
X553587Y1346026D03*
X527000Y1340600D03*
X521500Y1342800D03*
X585479Y537731D03*
Y543994D03*
X609334Y538306D03*
Y543306D03*
X631540Y589451D03*
X658574Y930100D03*
X699883Y916689D03*
X700383Y940189D03*
X706084Y881450D03*
X746800Y872700D03*
X713883Y890189D03*
X727883Y877189D03*
X743000Y886200D03*
X737687Y872489D03*
X743200Y881658D03*
X731866Y873789D03*
X740883Y920189D03*
X740383Y911689D03*
X737683Y899989D03*
X746183Y901389D03*
X743883Y893289D03*
X768770Y868643D03*
X776400Y956500D03*
X782230Y1323670D03*
X785340Y1320410D03*
X789549Y1322310D03*
X781290Y1328490D03*
X790290Y1328410D03*
X785640Y1328370D03*
X863900Y463100D03*
X848325Y480275D03*
X866100Y479900D03*
X856900Y479950D03*
X873000Y479900D03*
X864100Y492800D03*
X854600Y493000D03*
X891800Y1349965D03*
X888856Y1537644D03*
X941841Y1258580D03*
X903539Y1305368D03*
X920552Y1284112D03*
X963780Y1022400D03*
X966081Y1230097D03*
X954700Y1524100D03*
Y1530363D03*
X974787Y1525100D03*
Y1529300D03*
X1040180Y437510D03*
X1028657Y1009103D03*
X1026100Y1363300D03*
X1023700Y1359525D03*
X1022232Y1414851D03*
X1039845Y1467746D03*
X1026345D03*
X1030845D03*
X1035345D03*
X1039845Y1463246D03*
X1026345D03*
X1030845D03*
X1035345D03*
X1005400Y1463157D03*
X1000900D03*
X996400D03*
X1009900D03*
X1005400Y1467657D03*
X1000900D03*
X996400D03*
X1009900D03*
X1035345Y1476746D03*
X1030845D03*
X1026345D03*
X1039845D03*
Y1472246D03*
X1026345D03*
X1030845D03*
X1035345D03*
X1005400Y1472157D03*
X1000900D03*
X996400D03*
X1009900D03*
Y1476657D03*
X1005400D03*
X1000900D03*
X996400D03*
X1023583Y1489593D03*
X995783D03*
X1000500Y1511400D03*
X1036578Y1511210D03*
X1014690Y1511178D03*
X1010190D03*
X1005690D03*
X1031790Y1511078D03*
X1027290D03*
X1019600Y1511100D03*
X1023583Y1501593D03*
Y1507593D03*
Y1495593D03*
X995783D03*
Y1501593D03*
Y1507593D03*
X1040583Y1517883D03*
X1031799Y1534392D03*
X1031882Y1528985D03*
X1026459Y1528919D03*
X1026376Y1534326D03*
X1014867D03*
X1014950Y1528919D03*
X1020290Y1534392D03*
X1020373Y1528985D03*
X1040500Y1529290D03*
X1040583Y1523883D03*
X1035600Y1520600D03*
X1079455Y-30742D03*
X1043674Y451921D03*
X1073408Y942399D03*
X1058571Y943852D03*
X1055881Y1006428D03*
X1065475Y1013261D03*
X1062700Y1463100D03*
X1058200D03*
X1067200D03*
X1062700Y1467600D03*
X1058200D03*
X1067200D03*
X1053700Y1463100D03*
Y1467600D03*
X1062700Y1472100D03*
X1058200D03*
X1067200D03*
Y1476600D03*
X1058200D03*
X1062700D03*
X1053700Y1472100D03*
Y1476600D03*
X1047700Y1481500D03*
X1078683Y1489593D03*
X1051383D03*
X1041810Y1511084D03*
X1055310D03*
X1059810D03*
X1064310D03*
X1068810D03*
X1073310D03*
X1078683Y1495593D03*
Y1501593D03*
Y1507593D03*
Y1516593D03*
X1051383Y1495593D03*
Y1501593D03*
Y1507593D03*
X1078683Y1522593D03*
X1124024Y-30840D03*
X1128765Y-34297D03*
X1111254Y-31020D03*
X1105328Y-31005D03*
X1146768Y-31238D03*
X1139808Y-31171D03*
X1149699Y-35153D03*
X1142293Y-37522D03*
X1215795Y181242D03*
X1324207Y138756D03*
X1315102Y137903D03*
X1316000Y772200D03*
X1312767Y885535D03*
X1375700Y413400D03*
X1347600Y734078D03*
X1344062Y737800D03*
X1354500Y747304D03*
X1360920Y749829D03*
X1334300Y771200D03*
X1338729Y776131D03*
X1338700Y771500D03*
X1373519Y761900D03*
X1369600Y1330100D03*
X1373700Y1330000D03*
X1414882Y397271D03*
X1418225Y421700D03*
X1421239Y558029D03*
Y562229D03*
X1442500Y548400D03*
Y554700D03*
X1474083Y764750D03*
X1471608Y768500D03*
X1500539Y739639D03*
X1498000Y743000D03*
X1489000Y723000D03*
X1476558Y759088D03*
X1479033Y762259D03*
X1486600Y786559D03*
X1494662Y1336000D03*
X1548021Y544100D03*
X1554813Y548500D03*
X1713879Y1005156D03*
X1719681Y1015301D03*
X1799100Y1018400D03*
X1783963Y1018325D03*
X1775863Y1015225D03*
X1843200Y912813D03*
X1825821Y907899D03*
X1841065D03*
X1860570Y936809D03*
X1842000Y1344700D03*
X1867763Y805386D03*
X1896801Y875796D03*
X1901442Y884012D03*
X1906010Y880553D03*
X1892673Y913996D03*
X1901442Y901000D03*
X1891098Y933500D03*
X1891616Y925702D03*
X1886814Y929000D03*
X1897507Y905750D03*
X1872024Y932518D03*
X1892473Y942674D03*
X1911676Y900821D03*
G54D28*
X93100Y971000D03*
X159800Y559000D03*
X741883Y865289D03*
X703883Y911889D03*
X707332Y939902D03*
X750968Y896298D03*
X961000Y1516900D03*
X1733218Y991829D03*
X1891877Y877003D03*
G54D82*
X1868276Y916059D03*
G54D64*
X719819Y865905D03*
X1885126Y917859D03*
G54D46*
X173228Y1114173D03*
X670079D03*
X1343700D03*
X1840551D03*
G54D37*
X172911Y968100D03*
X138289D03*
X204989Y556100D03*
X239611D03*
X1814711Y980100D03*
X1780089D03*
G54D73*
X874800Y467500D03*
X850100Y473300D03*
X1436200Y561900D03*
X1893500Y909300D03*
G54D19*
X80019Y51968D03*
X127263Y20472D03*
X631200Y51968D03*
X678444Y20472D03*
X1250689Y51969D03*
X1297933Y20472D03*
X1801870Y51969D03*
X1849114Y20472D03*
G54D55*
X711711Y884900D03*
X743200Y878000D03*
X729182Y865902D03*
X874900Y475000D03*
X872000Y487700D03*
X856900Y487900D03*
X866100Y487800D03*
X1889500Y909200D03*
X1892443Y900950D03*
X1888000Y890700D03*
G54D29*
X93100Y974600D03*
X159800Y562600D03*
X741883Y868889D03*
X703883Y915489D03*
X707332Y943502D03*
X750968Y899898D03*
X961000Y1520500D03*
X1733218Y995429D03*
X1891877Y880603D03*
G54D38*
X129000Y997700D03*
X195500Y585700D03*
X749383Y915989D03*
X855400Y458500D03*
X1429400Y558100D03*
Y562100D03*
X1770800Y1009700D03*
X1886450Y880323D03*
X1900200Y938000D03*
Y921000D03*
Y925000D03*
G54D47*
X191400Y987400D03*
Y948300D03*
Y973100D03*
Y1012200D03*
X258100Y536300D03*
Y600200D03*
Y575400D03*
Y561100D03*
X1833200Y987700D03*
Y948600D03*
Y973400D03*
Y1012500D03*
G54D83*
X1860402Y925702D03*
X1858433D03*
Y906416D03*
X1860402D03*
X1878119Y925702D03*
X1876150D03*
X1874182D03*
X1872213D03*
X1870245D03*
X1868276D03*
X1866307D03*
X1864339D03*
X1862370D03*
Y906416D03*
X1864339D03*
X1866307D03*
X1868276D03*
X1870245D03*
X1872213D03*
X1874182D03*
X1876150D03*
X1878119D03*
G54D74*
X874800Y463900D03*
X850100Y469700D03*
X1436200Y558300D03*
X1893500Y905700D03*
G54D56*
X745983Y864989D03*
X714054Y876958D03*
X738282Y904102D03*
X859600Y458600D03*
X967800Y1516700D03*
Y1520700D03*
X1896800Y933500D03*
Y929000D03*
G54D65*
X719119Y858953D03*
X988795Y1571058D03*
Y1576658D03*
X1026106Y1545595D03*
Y1539995D03*
X1031706Y1545595D03*
Y1539995D03*
X1020574Y1540059D03*
Y1545659D03*
X1039758Y1559605D03*
X1014974Y1540059D03*
Y1545659D03*
X1039358Y1565405D03*
X1033717Y1563634D03*
X1028223Y1563763D03*
X1022623D03*
X994305Y1566342D03*
X1017023Y1563763D03*
X1011476Y1565175D03*
X1005658Y1565005D03*
X1000058D03*
X1039958Y1553705D03*
Y1548105D03*
Y1542505D03*
X1039358Y1571005D03*
Y1576605D03*
X1005658Y1575905D03*
X1033917Y1574834D03*
X1033717Y1569234D03*
X1000058Y1575905D03*
X1028423Y1574963D03*
X1028223Y1569363D03*
X994460Y1577240D03*
X1022823Y1574963D03*
X1022623Y1569363D03*
X1017223Y1574963D03*
X1017023Y1569363D03*
X994305Y1571942D03*
X1011676Y1576375D03*
X1011476Y1570775D03*
X1005658Y1570605D03*
X1000058D03*
X1078358Y1561105D03*
Y1566705D03*
X1072758Y1561105D03*
Y1566705D03*
X1067158Y1561105D03*
Y1566705D03*
X1061558Y1561105D03*
Y1566705D03*
X1055768Y1566675D03*
X1055418Y1560785D03*
X1055618Y1554885D03*
Y1549285D03*
Y1543685D03*
X1078358Y1572305D03*
X1072758D03*
X1067158D03*
X1061558D03*
X1055768Y1572275D03*
Y1577875D03*
X1898000Y888500D03*
G54D84*
G01X394744Y-485863D02*
X395618Y-484988D01*
X396273Y-483530D01*
X396710Y-481487D01*
X396273Y-479738D01*
X395400Y-478571D01*
X393871Y-477696D01*
X387976D01*
Y-495196D01*
X395181D01*
X396710Y-494030D01*
X397583Y-492279D01*
X398020Y-490238D01*
X397583Y-488196D01*
X396273Y-486446D01*
X394744Y-485863D01*
X387976D01*
G01X407441Y-495196D02*
Y-483530D01*
G01Y-485863D02*
X408533Y-484696D01*
X409625Y-483821D01*
X411153Y-483530D01*
X412244Y-483821D01*
X413555Y-484696D01*
G01X423413Y-500446D02*
X424723Y-501029D01*
X426470Y-500446D01*
X427561Y-499280D01*
X428435Y-497821D01*
X429744Y-493155D01*
X432583Y-483530D01*
G01X425596D02*
X429744Y-493155D01*
G01X448991Y-484988D02*
X447463Y-483821D01*
X446153Y-483530D01*
X444406Y-484113D01*
X443096Y-485279D01*
X442223Y-487321D01*
X442004Y-489363D01*
X442223Y-491405D01*
X443096Y-493155D01*
X444406Y-494613D01*
X446153Y-495196D01*
X447681Y-494613D01*
X448991Y-493446D01*
G01X459723Y-487321D02*
X466710D01*
X466055Y-485279D01*
X464963Y-484113D01*
X463435Y-483530D01*
X461906Y-483821D01*
X460596Y-484696D01*
X459723Y-486738D01*
X459286Y-488488D01*
Y-490238D01*
X459723Y-491988D01*
X460815Y-493738D01*
X462125Y-494904D01*
X463653Y-495196D01*
X465181Y-494613D01*
X466710Y-492863D01*
G01X502801Y-479155D02*
X501491Y-478279D01*
X499963Y-477696D01*
X498216D01*
X496251Y-478571D01*
X494723Y-480029D01*
X493631Y-481780D01*
X492758Y-484696D01*
X492539Y-487321D01*
X492976Y-489946D01*
X493631Y-491696D01*
X494941Y-493446D01*
X496470Y-494613D01*
X497998Y-495196D01*
X499526D01*
X501055Y-494613D01*
X502365Y-493738D01*
X503457Y-492572D01*
G01X519428Y-495196D02*
Y-483530D01*
G01Y-485571D02*
X518555Y-484405D01*
X517244Y-483821D01*
X515716Y-483530D01*
X514188Y-484113D01*
X512878Y-485279D01*
X512004Y-487029D01*
X511568Y-489363D01*
X512004Y-491696D01*
X512878Y-493446D01*
X514188Y-494613D01*
X515716Y-495196D01*
X517244Y-494904D01*
X518555Y-494030D01*
X519428Y-492863D01*
G01X529286Y-495196D02*
Y-483530D01*
G01Y-486446D02*
X530160Y-484988D01*
X531470Y-483821D01*
X533216Y-483530D01*
X534744Y-483821D01*
X536055Y-484988D01*
X536710Y-487029D01*
Y-495196D01*
G01X545913Y-500446D02*
X547223Y-501029D01*
X548970Y-500446D01*
X550061Y-499280D01*
X550935Y-497821D01*
X552244Y-493155D01*
X555083Y-483530D01*
G01X548096D02*
X552244Y-493155D01*
G01X567998Y-495196D02*
X566688Y-494904D01*
X565378Y-493738D01*
X564504Y-491696D01*
X564068Y-489363D01*
X564504Y-487029D01*
X565378Y-484988D01*
X566688Y-483821D01*
X567998Y-483530D01*
X569308Y-483821D01*
X570618Y-484988D01*
X571491Y-487029D01*
X571710Y-489363D01*
X571491Y-491696D01*
X570618Y-493738D01*
X569308Y-494904D01*
X567998Y-495196D01*
G01X581786D02*
Y-483530D01*
G01Y-486446D02*
X582660Y-484988D01*
X583970Y-483821D01*
X585716Y-483530D01*
X587244Y-483821D01*
X588555Y-484988D01*
X589210Y-487029D01*
Y-495196D01*
G01X616350D02*
Y-477696D01*
X624646D01*
G01X621590Y-486154D02*
X616350D01*
G01X637998Y-495779D02*
X637561Y-495488D01*
Y-494904D01*
X637998Y-494613D01*
X638435Y-494904D01*
Y-495488D01*
X637998Y-495779D01*
G01X650695Y-495196D02*
Y-477696D01*
X655061D01*
X656808Y-478571D01*
X658118Y-479738D01*
X659210Y-481487D01*
X660083Y-483530D01*
X660301Y-486446D01*
X660083Y-489363D01*
X659210Y-491405D01*
X658118Y-493155D01*
X656808Y-494321D01*
X655061Y-495196D01*
X650695D01*
G01X668631D02*
Y-477696D01*
X673871D01*
X675618Y-478571D01*
X676928Y-480613D01*
X677365Y-482946D01*
X676928Y-485279D01*
X675836Y-487029D01*
X673871Y-487905D01*
X668631D01*
G01X692244Y-485863D02*
X693118Y-484988D01*
X693773Y-483530D01*
X694210Y-481487D01*
X693773Y-479738D01*
X692900Y-478571D01*
X691371Y-477696D01*
X685476D01*
Y-495196D01*
X692681D01*
X694210Y-494030D01*
X695083Y-492279D01*
X695520Y-490238D01*
X695083Y-488196D01*
X693773Y-486446D01*
X692244Y-485863D01*
X685476D01*
G01X501071Y-450196D02*
Y-432696D01*
X506748Y-447279D01*
X512425Y-432696D01*
Y-450196D01*
G01X524248D02*
X522938Y-449904D01*
X521628Y-448738D01*
X520754Y-446696D01*
X520318Y-444363D01*
X520754Y-442029D01*
X521628Y-439988D01*
X522938Y-438821D01*
X524248Y-438530D01*
X525558Y-438821D01*
X526868Y-439988D01*
X527741Y-442029D01*
X527960Y-444363D01*
X527741Y-446696D01*
X526868Y-448738D01*
X525558Y-449904D01*
X524248Y-450196D01*
G01X545678Y-432696D02*
Y-450196D01*
G01Y-447572D02*
X544805Y-449030D01*
X543494Y-449904D01*
X541966Y-450196D01*
X540220Y-449613D01*
X538910Y-448155D01*
X538036Y-446405D01*
X537818Y-444363D01*
X538036Y-442321D01*
X538910Y-440571D01*
X540220Y-439113D01*
X541966Y-438530D01*
X543494Y-438821D01*
X544586Y-439405D01*
X545678Y-440571D01*
G01X555973Y-442321D02*
X562960D01*
X562305Y-440279D01*
X561213Y-439113D01*
X559685Y-438530D01*
X558156Y-438821D01*
X556846Y-439696D01*
X555973Y-441738D01*
X555536Y-443488D01*
Y-445238D01*
X555973Y-446988D01*
X557065Y-448738D01*
X558375Y-449904D01*
X559903Y-450196D01*
X561431Y-449613D01*
X562960Y-447863D01*
G01X576748Y-450196D02*
Y-432696D01*
G01X754448Y-495196D02*
Y-477696D01*
X751828Y-481196D01*
G01Y-495196D02*
X757068D01*
G01X767800Y-487905D02*
X769328Y-485863D01*
X770638Y-484696D01*
X772385Y-484113D01*
X773913Y-484696D01*
X775005Y-485863D01*
X775878Y-487613D01*
X776096Y-489654D01*
X775878Y-491405D01*
X775005Y-493155D01*
X773694Y-494613D01*
X772166Y-495196D01*
X770420Y-494613D01*
X768891Y-492863D01*
X768018Y-490238D01*
X767800Y-487321D01*
X768236Y-483530D01*
X768891Y-481487D01*
X769983Y-479446D01*
X771511Y-477988D01*
X773040Y-477696D01*
X774568Y-478279D01*
X775660Y-479738D01*
G01X784645Y-491696D02*
X785954Y-493738D01*
X787701Y-494904D01*
X789666Y-495196D01*
X791413Y-494904D01*
X793160Y-493446D01*
X794251Y-491696D01*
X794470Y-489946D01*
X794033Y-487905D01*
X792505Y-486446D01*
X790976Y-485863D01*
X789011D01*
G01X790976D02*
X792286Y-484988D01*
X793378Y-483530D01*
X793815Y-481780D01*
X793378Y-480029D01*
X792286Y-478571D01*
X790321Y-477696D01*
X788356Y-477988D01*
X786391Y-479155D01*
G01X806948Y-495196D02*
Y-477696D01*
X804328Y-481196D01*
G01Y-495196D02*
X809568D01*
G01X819645Y-492572D02*
X820954Y-494030D01*
X822483Y-494904D01*
X824448Y-495196D01*
X826413Y-494613D01*
X827941Y-493446D01*
X829033Y-491405D01*
X829251Y-489071D01*
X828815Y-486738D01*
X827723Y-485279D01*
X826194Y-484113D01*
X824666Y-483821D01*
X823138Y-484113D01*
X821173Y-485279D01*
X821828Y-477696D01*
X827723D01*
G01X741331Y-450196D02*
Y-432696D01*
X746571D01*
X748318Y-433571D01*
X749628Y-435613D01*
X750065Y-437946D01*
X749628Y-440279D01*
X748536Y-442029D01*
X746571Y-442905D01*
X741331D01*
G01X768001Y-434155D02*
X766691Y-433279D01*
X765163Y-432696D01*
X763416D01*
X761451Y-433571D01*
X759923Y-435029D01*
X758831Y-436780D01*
X757958Y-439696D01*
X757739Y-442321D01*
X758176Y-444946D01*
X758831Y-446696D01*
X760141Y-448446D01*
X761670Y-449613D01*
X763198Y-450196D01*
X764726D01*
X766255Y-449613D01*
X767565Y-448738D01*
X768657Y-447572D01*
G01X782444Y-440863D02*
X783318Y-439988D01*
X783973Y-438530D01*
X784410Y-436487D01*
X783973Y-434738D01*
X783100Y-433571D01*
X781571Y-432696D01*
X775676D01*
Y-450196D01*
X782881D01*
X784410Y-449030D01*
X785283Y-447279D01*
X785720Y-445238D01*
X785283Y-443196D01*
X783973Y-441446D01*
X782444Y-440863D01*
X775676D01*
G01X791648Y-456029D02*
X804748D01*
G01X810676Y-450196D02*
Y-432696D01*
X820720Y-450196D01*
Y-432696D01*
G01X833198Y-450196D02*
X831451Y-449904D01*
X829923Y-448738D01*
X828613Y-446988D01*
X827739Y-444946D01*
X827303Y-442613D01*
Y-440279D01*
X827739Y-437946D01*
X828613Y-435904D01*
X829923Y-434155D01*
X831451Y-432988D01*
X833198Y-432696D01*
X834944Y-432988D01*
X836473Y-434155D01*
X837783Y-435904D01*
X838657Y-437946D01*
X839093Y-440279D01*
Y-442613D01*
X838657Y-444946D01*
X837783Y-446988D01*
X836473Y-448738D01*
X834944Y-449904D01*
X833198Y-450196D01*
G01X884039Y-432696D02*
X889498Y-450196D01*
X894957Y-432696D01*
G01X911365Y-450196D02*
X902631D01*
Y-432696D01*
X911365D01*
G01X907871Y-441154D02*
X902631D01*
G01X920131Y-450196D02*
Y-432696D01*
X925590D01*
X927336Y-433571D01*
X928428Y-434738D01*
X928865Y-437071D01*
X928428Y-439405D01*
X927118Y-440863D01*
X925590Y-441738D01*
X920131D01*
G01X925590D02*
X928865Y-450196D01*
G01X941998Y-450779D02*
X941561Y-450488D01*
Y-449904D01*
X941998Y-449613D01*
X942435Y-449904D01*
Y-450488D01*
X941998Y-450779D01*
G01X915748Y-495196D02*
Y-477696D01*
X913128Y-481196D01*
G01Y-495196D02*
X918368D01*
G01X1155602Y-485863D02*
X1154728Y-484988D01*
X1154073Y-483530D01*
X1153636Y-481487D01*
X1154073Y-479738D01*
X1154946Y-478571D01*
X1156475Y-477696D01*
X1162370D01*
Y-495196D01*
X1155165D01*
X1153636Y-494030D01*
X1152763Y-492279D01*
X1152326Y-490238D01*
X1152763Y-488196D01*
X1154073Y-486446D01*
X1155602Y-485863D01*
X1162370D01*
G01X1145525Y-495196D02*
Y-477696D01*
X1139848Y-492279D01*
X1134171Y-477696D01*
Y-495196D01*
G01X1127807D02*
X1122348Y-477696D01*
X1116889Y-495196D01*
G01X1118855Y-489071D02*
X1125842D01*
G01X1109433Y-492863D02*
X1107686Y-494321D01*
X1105721Y-495196D01*
X1103975D01*
X1102228Y-494321D01*
X1100918Y-492863D01*
X1100263Y-490821D01*
X1100700Y-488780D01*
X1101791Y-487029D01*
X1103756Y-485863D01*
X1106376Y-485279D01*
X1107905Y-484113D01*
X1108560Y-482071D01*
X1108123Y-480029D01*
X1107031Y-478571D01*
X1105503Y-477696D01*
X1103975D01*
X1102446Y-478279D01*
X1101136Y-479738D01*
G01X1092151Y-495196D02*
Y-477696D01*
G01X1083855D02*
X1092151Y-488488D01*
G01X1082545Y-495196D02*
X1088440Y-483530D01*
G01X1082981Y-432696D02*
Y-450196D01*
X1091715D01*
G01X1108778D02*
Y-438530D01*
G01Y-440571D02*
X1107905Y-439405D01*
X1106594Y-438821D01*
X1105066Y-438530D01*
X1103538Y-439113D01*
X1102228Y-440279D01*
X1101354Y-442029D01*
X1100918Y-444363D01*
X1101354Y-446696D01*
X1102228Y-448446D01*
X1103538Y-449613D01*
X1105066Y-450196D01*
X1106594Y-449904D01*
X1107905Y-449030D01*
X1108778Y-447863D01*
G01X1117763Y-455446D02*
X1119073Y-456029D01*
X1120820Y-455446D01*
X1121911Y-454280D01*
X1122785Y-452821D01*
X1124094Y-448155D01*
X1126933Y-438530D01*
G01X1119946D02*
X1124094Y-448155D01*
G01X1136573Y-442321D02*
X1143560D01*
X1142905Y-440279D01*
X1141813Y-439113D01*
X1140285Y-438530D01*
X1138756Y-438821D01*
X1137446Y-439696D01*
X1136573Y-441738D01*
X1136136Y-443488D01*
Y-445238D01*
X1136573Y-446988D01*
X1137665Y-448738D01*
X1138975Y-449904D01*
X1140503Y-450196D01*
X1142031Y-449613D01*
X1143560Y-447863D01*
G01X1154291Y-450196D02*
Y-438530D01*
G01Y-440863D02*
X1155383Y-439696D01*
X1156475Y-438821D01*
X1158003Y-438530D01*
X1159094Y-438821D01*
X1160405Y-439696D01*
G01X1312898Y-495196D02*
X1311151Y-494904D01*
X1309623Y-493738D01*
X1308313Y-491988D01*
X1307439Y-489946D01*
X1307003Y-487613D01*
Y-485279D01*
X1307439Y-482946D01*
X1308313Y-480904D01*
X1309623Y-479155D01*
X1311151Y-477988D01*
X1312898Y-477696D01*
X1314644Y-477988D01*
X1316173Y-479155D01*
X1317483Y-480904D01*
X1318357Y-482946D01*
X1318793Y-485279D01*
Y-487613D01*
X1318357Y-489946D01*
X1317483Y-491988D01*
X1316173Y-493738D01*
X1314644Y-494904D01*
X1312898Y-495196D01*
G01X1314644Y-490529D02*
X1317265Y-495196D01*
G01X1325595Y-477696D02*
Y-490238D01*
X1326468Y-492863D01*
X1328215Y-494613D01*
X1330398Y-495196D01*
X1332581Y-494613D01*
X1334328Y-492863D01*
X1335201Y-490238D01*
Y-477696D01*
G01X1345278D02*
X1350518D01*
G01X1347898D02*
Y-495196D01*
G01X1345278D02*
X1350518D01*
G01X1360376D02*
Y-477696D01*
X1370420Y-495196D01*
Y-477696D01*
G01X1387701Y-479155D02*
X1386391Y-478279D01*
X1384863Y-477696D01*
X1383116D01*
X1381151Y-478571D01*
X1379623Y-480029D01*
X1378531Y-481780D01*
X1377658Y-484696D01*
X1377439Y-487321D01*
X1377876Y-489946D01*
X1378531Y-491696D01*
X1379841Y-493446D01*
X1381370Y-494613D01*
X1382898Y-495196D01*
X1384426D01*
X1385955Y-494613D01*
X1387265Y-493738D01*
X1388357Y-492572D01*
G01X1400398Y-495196D02*
Y-487321D01*
X1396031Y-477696D01*
G01X1404765D02*
X1400398Y-487321D01*
G01X1290595Y-450196D02*
Y-432696D01*
X1294961D01*
X1296708Y-433571D01*
X1298018Y-434738D01*
X1299110Y-436487D01*
X1299983Y-438530D01*
X1300201Y-441446D01*
X1299983Y-444363D01*
X1299110Y-446405D01*
X1298018Y-448155D01*
X1296708Y-449321D01*
X1294961Y-450196D01*
X1290595D01*
G01X1309623Y-442321D02*
X1316610D01*
X1315955Y-440279D01*
X1314863Y-439113D01*
X1313335Y-438530D01*
X1311806Y-438821D01*
X1310496Y-439696D01*
X1309623Y-441738D01*
X1309186Y-443488D01*
Y-445238D01*
X1309623Y-446988D01*
X1310715Y-448738D01*
X1312025Y-449904D01*
X1313553Y-450196D01*
X1315081Y-449613D01*
X1316610Y-447863D01*
G01X1327123Y-448155D02*
X1328215Y-449321D01*
X1329743Y-450196D01*
X1331053D01*
X1332363Y-449613D01*
X1333236Y-448738D01*
X1333673Y-447572D01*
X1333455Y-445821D01*
X1332581Y-444946D01*
X1328651Y-443196D01*
X1327778Y-441154D01*
X1328215Y-439696D01*
X1329088Y-438821D01*
X1330398Y-438530D01*
X1331708Y-438821D01*
X1333018Y-439696D01*
G01X1347898Y-438530D02*
Y-450196D01*
G01Y-433863D02*
X1347461Y-433571D01*
Y-432988D01*
X1347898Y-432696D01*
X1348335Y-432988D01*
Y-433571D01*
X1347898Y-433863D01*
G01X1362341Y-454571D02*
X1363870Y-455738D01*
X1365616Y-456029D01*
X1367144Y-455738D01*
X1368455Y-454280D01*
X1369328Y-452238D01*
Y-438530D01*
G01Y-440863D02*
X1368455Y-439696D01*
X1367144Y-438821D01*
X1365616Y-438530D01*
X1363870Y-439113D01*
X1362778Y-440279D01*
X1361904Y-442321D01*
X1361468Y-444363D01*
X1361686Y-446113D01*
X1362560Y-448155D01*
X1363870Y-449613D01*
X1365616Y-450196D01*
X1366926Y-449904D01*
X1368455Y-448738D01*
X1369328Y-447572D01*
G01X1379186Y-450196D02*
Y-438530D01*
G01Y-441446D02*
X1380060Y-439988D01*
X1381370Y-438821D01*
X1383116Y-438530D01*
X1384644Y-438821D01*
X1385955Y-439988D01*
X1386610Y-442029D01*
Y-450196D01*
G01X1397123Y-442321D02*
X1404110D01*
X1403455Y-440279D01*
X1402363Y-439113D01*
X1400835Y-438530D01*
X1399306Y-438821D01*
X1397996Y-439696D01*
X1397123Y-441738D01*
X1396686Y-443488D01*
Y-445238D01*
X1397123Y-446988D01*
X1398215Y-448738D01*
X1399525Y-449904D01*
X1401053Y-450196D01*
X1402581Y-449613D01*
X1404110Y-447863D01*
G01X1414841Y-450196D02*
Y-438530D01*
G01Y-440863D02*
X1415933Y-439696D01*
X1417025Y-438821D01*
X1418553Y-438530D01*
X1419644Y-438821D01*
X1420955Y-439696D01*
G01X1461598Y-477696D02*
X1459851Y-478279D01*
X1458541Y-479738D01*
X1457668Y-481487D01*
X1457013Y-483821D01*
X1456795Y-486446D01*
X1457013Y-489071D01*
X1457668Y-491405D01*
X1458541Y-493155D01*
X1459851Y-494613D01*
X1461598Y-495196D01*
X1463344Y-494613D01*
X1464655Y-493155D01*
X1465528Y-491405D01*
X1466183Y-489071D01*
X1466401Y-486446D01*
X1466183Y-483821D01*
X1465528Y-481487D01*
X1464655Y-479738D01*
X1463344Y-478279D01*
X1461598Y-477696D01*
G01X1474950Y-487905D02*
X1476478Y-485863D01*
X1477788Y-484696D01*
X1479535Y-484113D01*
X1481063Y-484696D01*
X1482155Y-485863D01*
X1483028Y-487613D01*
X1483246Y-489654D01*
X1483028Y-491405D01*
X1482155Y-493155D01*
X1480844Y-494613D01*
X1479316Y-495196D01*
X1477570Y-494613D01*
X1476041Y-492863D01*
X1475168Y-490238D01*
X1474950Y-487321D01*
X1475386Y-483530D01*
X1476041Y-481487D01*
X1477133Y-479446D01*
X1478661Y-477988D01*
X1480190Y-477696D01*
X1481718Y-478279D01*
X1482810Y-479738D01*
G01X1492668Y-495779D02*
X1500528Y-477696D01*
G01X1514098D02*
X1512351Y-478279D01*
X1511041Y-479738D01*
X1510168Y-481487D01*
X1509513Y-483821D01*
X1509295Y-486446D01*
X1509513Y-489071D01*
X1510168Y-491405D01*
X1511041Y-493155D01*
X1512351Y-494613D01*
X1514098Y-495196D01*
X1515844Y-494613D01*
X1517155Y-493155D01*
X1518028Y-491405D01*
X1518683Y-489071D01*
X1518901Y-486446D01*
X1518683Y-483821D01*
X1518028Y-481487D01*
X1517155Y-479738D01*
X1515844Y-478279D01*
X1514098Y-477696D01*
G01X1527886Y-493155D02*
X1529415Y-494613D01*
X1531161Y-495196D01*
X1532908Y-494613D01*
X1534436Y-492863D01*
X1535528Y-490238D01*
X1535965Y-487613D01*
Y-484405D01*
X1535528Y-481780D01*
X1534436Y-479446D01*
X1533126Y-478279D01*
X1531598Y-477696D01*
X1529851Y-478279D01*
X1528541Y-479446D01*
X1527668Y-481196D01*
X1527231Y-483530D01*
X1527668Y-485571D01*
X1528760Y-487613D01*
X1530070Y-488780D01*
X1531598Y-489071D01*
X1533344Y-488488D01*
X1534655Y-487029D01*
X1535965Y-484405D01*
G01X1545168Y-495779D02*
X1553028Y-477696D01*
G01X1562450Y-480613D02*
X1563760Y-478863D01*
X1565288Y-477988D01*
X1567035Y-477696D01*
X1569218Y-478279D01*
X1570746Y-479738D01*
X1571183Y-481487D01*
X1570965Y-483238D01*
X1570091Y-484696D01*
X1565725Y-487613D01*
X1563760Y-489654D01*
X1562450Y-492572D01*
X1562013Y-495196D01*
X1571183D01*
G01X1584098Y-477696D02*
X1582351Y-478279D01*
X1581041Y-479738D01*
X1580168Y-481487D01*
X1579513Y-483821D01*
X1579295Y-486446D01*
X1579513Y-489071D01*
X1580168Y-491405D01*
X1581041Y-493155D01*
X1582351Y-494613D01*
X1584098Y-495196D01*
X1585844Y-494613D01*
X1587155Y-493155D01*
X1588028Y-491405D01*
X1588683Y-489071D01*
X1588901Y-486446D01*
X1588683Y-483821D01*
X1588028Y-481487D01*
X1587155Y-479738D01*
X1585844Y-478279D01*
X1584098Y-477696D01*
G01X1601598Y-495196D02*
Y-477696D01*
X1598978Y-481196D01*
G01Y-495196D02*
X1604218D01*
G01X1618661D02*
X1619098Y-491405D01*
X1619753Y-488196D01*
X1620626Y-485279D01*
X1621718Y-482071D01*
X1623465Y-477696D01*
X1614731D01*
G01X1509295Y-450196D02*
Y-432696D01*
X1513661D01*
X1515408Y-433571D01*
X1516718Y-434738D01*
X1517810Y-436487D01*
X1518683Y-438530D01*
X1518901Y-441446D01*
X1518683Y-444363D01*
X1517810Y-446405D01*
X1516718Y-448155D01*
X1515408Y-449321D01*
X1513661Y-450196D01*
X1509295D01*
G01X1535528D02*
Y-438530D01*
G01Y-440571D02*
X1534655Y-439405D01*
X1533344Y-438821D01*
X1531816Y-438530D01*
X1530288Y-439113D01*
X1528978Y-440279D01*
X1528104Y-442029D01*
X1527668Y-444363D01*
X1528104Y-446696D01*
X1528978Y-448446D01*
X1530288Y-449613D01*
X1531816Y-450196D01*
X1533344Y-449904D01*
X1534655Y-449030D01*
X1535528Y-447863D01*
G01X1549098Y-432696D02*
Y-450196D01*
G01X1546041Y-438530D02*
X1552155D01*
G01X1563323Y-442321D02*
X1570310D01*
X1569655Y-440279D01*
X1568563Y-439113D01*
X1567035Y-438530D01*
X1565506Y-438821D01*
X1564196Y-439696D01*
X1563323Y-441738D01*
X1562886Y-443488D01*
Y-445238D01*
X1563323Y-446988D01*
X1564415Y-448738D01*
X1565725Y-449904D01*
X1567253Y-450196D01*
X1568781Y-449613D01*
X1570310Y-447863D01*
G54D39*
X125600Y997700D03*
X192100Y585700D03*
X745983Y915989D03*
X852000Y458500D03*
X1426000Y558100D03*
Y562100D03*
X1767400Y1009700D03*
X1883050Y880323D03*
X1896800Y938000D03*
Y921000D03*
Y925000D03*
G54D75*
X866100Y468545D03*
Y470515D03*
Y472485D03*
Y474455D03*
X856900D03*
Y472485D03*
Y470515D03*
Y468545D03*
G54D57*
X749383Y864989D03*
X717454Y876958D03*
X741682Y904102D03*
X863000Y458600D03*
X971200Y1516700D03*
Y1520700D03*
X1900200Y933500D03*
Y929000D03*
G54D66*
X733582Y862826D03*
X718552Y887720D03*
X746183Y905889D03*
X756717Y876889D03*
X751711Y876917D03*
X1876271Y936966D03*
X1888000Y895200D03*
G54D48*
X227063Y992475D03*
Y991975D03*
X293763Y580475D03*
Y579975D03*
X1867963Y993975D03*
Y993475D03*
G54D76*
X944881Y-58267D03*
G54D67*
X733582Y868426D03*
X746183Y911489D03*
X718552Y893320D03*
X756717Y882489D03*
X751711Y882517D03*
X1888000Y900800D03*
X1876271Y942566D03*
G54D58*
X730882Y888502D03*
G54D49*
X429724Y63977D03*
Y68307D03*
X443898Y63977D03*
X458071D03*
X436811Y67914D03*
X450984D03*
X458071Y68307D03*
X443898D03*
X429724Y116339D03*
Y92323D03*
Y96654D03*
Y102166D03*
Y106496D03*
Y110827D03*
Y87993D03*
Y82481D03*
Y78150D03*
Y73819D03*
X443898Y116339D03*
X458071D03*
X436811Y114764D03*
X450984D03*
X436811Y82087D03*
X450984D03*
X443898Y92323D03*
X458071D03*
X443898Y96654D03*
X458071D03*
X436811Y96260D03*
X450984D03*
X443898Y102166D03*
X458071D03*
X436811Y100591D03*
X450984D03*
X443898Y106496D03*
X458071D03*
X436811Y106103D03*
X450984D03*
X443898Y110827D03*
X458071D03*
X436811Y110433D03*
X450984D03*
X458071Y87993D03*
Y82481D03*
X450984Y91930D03*
Y86418D03*
X443898Y87993D03*
Y82481D03*
X436811Y91930D03*
Y86418D03*
X443898Y78150D03*
X458071D03*
Y73819D03*
X450984Y77756D03*
Y72245D03*
X443898Y73819D03*
X436811Y77756D03*
Y72245D03*
X429724Y120670D03*
X443898D03*
X458071D03*
X436811Y120276D03*
X450984D03*
X465157Y67914D03*
X472244Y63977D03*
X479331Y67914D03*
X472244Y68307D03*
X465157Y114764D03*
X472244Y116339D03*
X479331Y114764D03*
X465157Y82087D03*
Y96260D03*
Y100591D03*
Y106103D03*
Y110433D03*
X479331Y82087D03*
X472244Y92323D03*
Y96654D03*
X479331Y96260D03*
X472244Y102166D03*
X479331Y100591D03*
X472244Y106496D03*
X479331Y106103D03*
X472244Y110827D03*
X479331Y110433D03*
Y91930D03*
Y86418D03*
X472244Y87993D03*
Y82481D03*
X465157Y91930D03*
Y86418D03*
X472244Y78150D03*
X479331Y77756D03*
Y72245D03*
X472244Y73819D03*
X465157Y77756D03*
Y72245D03*
Y120276D03*
X472244Y120670D03*
X479331Y120276D03*
X514764Y63977D03*
Y68307D03*
X550197Y67914D03*
X536024D03*
X521850D03*
X543110Y63977D03*
X528937D03*
X543110Y68307D03*
X528937D03*
X557283Y63977D03*
Y68307D03*
X514764Y116339D03*
Y110827D03*
Y106496D03*
Y102166D03*
Y96654D03*
Y92323D03*
Y87993D03*
Y82481D03*
Y78150D03*
Y73819D03*
X550197Y114764D03*
X536024D03*
X521850D03*
X543110Y116339D03*
X528937D03*
X550197Y110433D03*
X536024D03*
X521850D03*
X543110Y110827D03*
X528937D03*
X550197Y106103D03*
X536024D03*
X521850D03*
X543110Y106496D03*
X528937D03*
X550197Y100591D03*
X536024D03*
X521850D03*
X543110Y102166D03*
X528937D03*
X550197Y96260D03*
X536024D03*
X521850D03*
X543110Y96654D03*
X528937D03*
X543110Y92323D03*
X528937D03*
X550197Y82087D03*
X536024D03*
X521850D03*
X550197Y91930D03*
Y86418D03*
X543110Y87993D03*
Y82481D03*
X536024Y91930D03*
Y86418D03*
X528937Y87993D03*
Y82481D03*
X521850Y91930D03*
Y86418D03*
X543110Y78150D03*
X528937D03*
X550197Y77756D03*
Y72245D03*
X543110Y73819D03*
X536024Y77756D03*
Y72245D03*
X528937Y73819D03*
X521850Y77756D03*
Y72245D03*
X557283Y116339D03*
Y110827D03*
Y106496D03*
Y102166D03*
Y96654D03*
Y92323D03*
Y87993D03*
Y82481D03*
Y78150D03*
Y73819D03*
X514764Y120670D03*
X550197Y120276D03*
X536024D03*
X521850D03*
X543110Y120670D03*
X528937D03*
X557283D03*
X564370Y67914D03*
Y114764D03*
Y110433D03*
Y106103D03*
Y100591D03*
Y96260D03*
Y82087D03*
Y91930D03*
Y86418D03*
Y77756D03*
Y72245D03*
Y120276D03*
X833859Y1594095D03*
Y1598425D03*
Y1603937D03*
Y1608268D03*
Y1612599D03*
X840945Y1598032D03*
X826772D03*
X840945Y1602363D03*
X826772D03*
X840945Y1607874D03*
X826772D03*
X840945Y1612205D03*
X826772D03*
X840945Y1616536D03*
X826772D03*
X833859Y1618111D03*
Y1622441D03*
Y1626772D03*
Y1632284D03*
Y1636614D03*
Y1640945D03*
Y1646457D03*
Y1650788D03*
X840945Y1622048D03*
X826772D03*
X840945Y1626378D03*
X826772D03*
X840945Y1630709D03*
X826772D03*
X840945Y1636221D03*
X826772D03*
X840945Y1640551D03*
X826772D03*
X840945Y1644882D03*
X826772D03*
X840945Y1650394D03*
X826772D03*
X876378Y1594095D03*
X862205D03*
X848032D03*
X876378Y1598425D03*
X862205D03*
X848032D03*
X876378Y1603937D03*
X862205D03*
X848032D03*
X876378Y1608268D03*
X862205D03*
X848032D03*
X876378Y1612599D03*
X862205D03*
X848032D03*
X890552Y1598032D03*
X869292D03*
X855118D03*
X890552Y1602363D03*
X869292D03*
X855118D03*
X890552Y1607874D03*
X869292D03*
X855118D03*
X890552Y1612205D03*
X869292D03*
X855118D03*
X890552Y1616536D03*
X869292D03*
X855118D03*
X876378Y1618111D03*
X862205D03*
X848032D03*
X876378Y1622441D03*
X862205D03*
X848032D03*
X876378Y1626772D03*
X862205D03*
X848032D03*
X876378Y1632284D03*
X862205D03*
X848032D03*
X876378Y1636614D03*
X862205D03*
X848032D03*
X876378Y1640945D03*
X862205D03*
X848032D03*
X876378Y1646457D03*
X862205D03*
X848032D03*
X876378Y1650788D03*
X862205D03*
X848032D03*
X890552Y1622048D03*
X869292D03*
X855118D03*
X890552Y1626378D03*
X869292D03*
X855118D03*
X890552Y1630709D03*
X869292D03*
X855118D03*
X890552Y1636221D03*
X869292D03*
X855118D03*
X890552Y1640551D03*
X869292D03*
X855118D03*
X890552Y1644882D03*
X869292D03*
X855118D03*
X890552Y1650394D03*
X869292D03*
X855118D03*
X911811Y1603937D03*
Y1608268D03*
Y1612599D03*
X904725Y1602363D03*
Y1607874D03*
Y1612205D03*
Y1616536D03*
X911811Y1594095D03*
Y1598425D03*
X904725Y1598032D03*
X897638Y1594095D03*
Y1598425D03*
Y1603937D03*
Y1608268D03*
Y1612599D03*
X911811Y1632284D03*
Y1636614D03*
Y1640945D03*
Y1646457D03*
Y1650788D03*
X904725Y1630709D03*
Y1636221D03*
Y1640551D03*
Y1644882D03*
Y1650394D03*
X911811Y1618111D03*
Y1622441D03*
Y1626772D03*
X904725Y1622048D03*
Y1626378D03*
X897638Y1618111D03*
Y1622441D03*
Y1626772D03*
Y1632284D03*
Y1636614D03*
Y1640945D03*
Y1646457D03*
Y1650788D03*
X1091089Y988592D03*
X1095420D03*
X1100932D03*
X1105262D03*
X1109593D03*
X1115105D03*
X1119435D03*
X1123766D03*
X1129278D03*
X1133609D03*
X1095026Y995678D03*
X1099357D03*
X1104869D03*
X1109199D03*
X1113530D03*
X1119042D03*
X1123372D03*
X1127703D03*
X1133215D03*
X1091089Y1002765D03*
X1095420D03*
X1100932D03*
X1105262D03*
X1109593D03*
X1115105D03*
X1119435D03*
X1123766D03*
X1129278D03*
X1133609D03*
X1095026Y1009852D03*
X1099357D03*
X1104869D03*
X1109199D03*
X1113530D03*
X1119042D03*
X1123372D03*
X1127703D03*
X1133215D03*
X1091089Y1016938D03*
X1095420D03*
X1100932D03*
X1105262D03*
X1109593D03*
X1115105D03*
X1119435D03*
X1123766D03*
X1129278D03*
X1133609D03*
X1095026Y1024025D03*
X1099357D03*
X1104869D03*
X1109199D03*
X1113530D03*
X1119042D03*
X1123372D03*
X1127703D03*
X1133215D03*
X1091089Y1031111D03*
X1095420D03*
X1100932D03*
X1105262D03*
X1109593D03*
X1115105D03*
X1119435D03*
X1123766D03*
X1129278D03*
X1133609D03*
X1095026Y1038198D03*
X1099357D03*
X1104869D03*
X1109199D03*
X1113530D03*
X1119042D03*
X1123372D03*
X1127703D03*
X1133215D03*
X1091089Y1160257D03*
Y1174430D03*
X1095420Y1160257D03*
Y1174430D03*
X1100932Y1160257D03*
Y1174430D03*
X1105262Y1160257D03*
Y1174430D03*
X1109593Y1160257D03*
Y1174430D03*
X1115105Y1160257D03*
Y1174430D03*
X1119435Y1160257D03*
Y1174430D03*
X1123766Y1160257D03*
Y1174430D03*
X1129278Y1160257D03*
Y1174430D03*
X1133609Y1160257D03*
Y1174430D03*
X1095026Y1167343D03*
X1099357D03*
X1104869D03*
X1109199D03*
X1113530D03*
X1119042D03*
X1123372D03*
X1127703D03*
X1133215D03*
X1091089Y1188603D03*
Y1202776D03*
Y1216949D03*
X1095420Y1188603D03*
Y1202776D03*
Y1216949D03*
X1100932Y1188603D03*
Y1202776D03*
Y1216949D03*
X1105262Y1188603D03*
Y1202776D03*
Y1216949D03*
X1109593Y1188603D03*
Y1202776D03*
Y1216949D03*
X1115105Y1188603D03*
Y1202776D03*
Y1216949D03*
X1119435Y1188603D03*
Y1202776D03*
Y1216949D03*
X1123766Y1188603D03*
Y1202776D03*
Y1216949D03*
X1129278Y1188603D03*
Y1202776D03*
Y1216949D03*
X1133609Y1188603D03*
Y1202776D03*
Y1216949D03*
X1095026Y1181516D03*
Y1195690D03*
Y1209863D03*
Y1224036D03*
X1099357Y1181516D03*
Y1195690D03*
Y1209863D03*
Y1224036D03*
X1104869Y1181516D03*
Y1195690D03*
Y1209863D03*
Y1224036D03*
X1109199Y1181516D03*
Y1195690D03*
Y1209863D03*
Y1224036D03*
X1113530Y1181516D03*
Y1195690D03*
Y1209863D03*
Y1224036D03*
X1119042Y1181516D03*
Y1195690D03*
Y1209863D03*
Y1224036D03*
X1123372Y1181516D03*
Y1195690D03*
Y1209863D03*
Y1224036D03*
X1127703Y1181516D03*
Y1195690D03*
Y1209863D03*
Y1224036D03*
X1133215Y1181516D03*
Y1195690D03*
Y1209863D03*
Y1224036D03*
X1091089Y1231123D03*
Y1245296D03*
Y1259469D03*
Y1273642D03*
X1095420Y1231123D03*
Y1245296D03*
Y1259469D03*
Y1273642D03*
X1100932Y1231123D03*
Y1245296D03*
Y1259469D03*
Y1273642D03*
X1105262Y1231123D03*
Y1245296D03*
Y1259469D03*
Y1273642D03*
X1109593Y1231123D03*
Y1245296D03*
Y1259469D03*
Y1273642D03*
X1115105Y1231123D03*
Y1245296D03*
Y1259469D03*
Y1273642D03*
X1119435Y1231123D03*
Y1245296D03*
Y1259469D03*
Y1273642D03*
X1123766Y1231123D03*
Y1245296D03*
Y1259469D03*
Y1273642D03*
X1129278Y1231123D03*
Y1245296D03*
Y1259469D03*
Y1273642D03*
X1133609Y1231123D03*
Y1245296D03*
Y1259469D03*
Y1273642D03*
X1095026Y1238209D03*
Y1252382D03*
Y1266556D03*
X1099357Y1238209D03*
Y1252382D03*
Y1266556D03*
X1104869Y1238209D03*
Y1252382D03*
Y1266556D03*
X1109199Y1238209D03*
Y1252382D03*
Y1266556D03*
X1113530Y1238209D03*
Y1252382D03*
Y1266556D03*
X1119042Y1238209D03*
Y1252382D03*
Y1266556D03*
X1123372Y1238209D03*
Y1252382D03*
Y1266556D03*
X1127703Y1238209D03*
Y1252382D03*
Y1266556D03*
X1133215Y1238209D03*
Y1252382D03*
Y1266556D03*
X1091089Y1287816D03*
Y1301989D03*
Y1316162D03*
X1095420Y1287816D03*
Y1301989D03*
Y1316162D03*
X1100932Y1287816D03*
Y1301989D03*
Y1316162D03*
X1105262Y1287816D03*
Y1301989D03*
Y1316162D03*
X1109593Y1287816D03*
Y1301989D03*
Y1316162D03*
X1115105Y1287816D03*
Y1301989D03*
Y1316162D03*
X1119435Y1287816D03*
Y1301989D03*
Y1316162D03*
X1123766Y1287816D03*
Y1301989D03*
Y1316162D03*
X1129278Y1287816D03*
Y1301989D03*
Y1316162D03*
X1133609Y1287816D03*
Y1301989D03*
Y1316162D03*
X1095026Y1280729D03*
Y1294902D03*
Y1309075D03*
Y1323249D03*
X1099357Y1280729D03*
Y1294902D03*
Y1309075D03*
Y1323249D03*
X1104869Y1280729D03*
Y1294902D03*
Y1309075D03*
Y1323249D03*
X1109199Y1280729D03*
Y1294902D03*
Y1309075D03*
Y1323249D03*
X1113530Y1280729D03*
Y1294902D03*
Y1309075D03*
Y1323249D03*
X1119042Y1280729D03*
Y1294902D03*
Y1309075D03*
Y1323249D03*
X1123372Y1280729D03*
Y1294902D03*
Y1309075D03*
Y1323249D03*
X1127703Y1280729D03*
Y1294902D03*
Y1309075D03*
Y1323249D03*
X1133215Y1280729D03*
Y1294902D03*
Y1309075D03*
Y1323249D03*
X1091089Y1330335D03*
Y1344508D03*
Y1358682D03*
Y1372855D03*
X1095420Y1330335D03*
Y1344508D03*
Y1358682D03*
Y1372855D03*
X1100932Y1330335D03*
Y1344508D03*
Y1358682D03*
Y1372855D03*
X1105262Y1330335D03*
Y1344508D03*
Y1358682D03*
Y1372855D03*
X1109593Y1330335D03*
Y1344508D03*
Y1358682D03*
Y1372855D03*
X1115105Y1330335D03*
Y1344508D03*
Y1358682D03*
Y1372855D03*
X1119435Y1330335D03*
Y1344508D03*
Y1358682D03*
Y1372855D03*
X1123766Y1330335D03*
Y1344508D03*
Y1358682D03*
Y1372855D03*
X1129278Y1330335D03*
Y1344508D03*
Y1358682D03*
Y1372855D03*
X1133609Y1330335D03*
Y1344508D03*
Y1358682D03*
Y1372855D03*
X1095026Y1337422D03*
Y1351595D03*
Y1365768D03*
X1099357Y1337422D03*
Y1351595D03*
Y1365768D03*
X1104869Y1337422D03*
Y1351595D03*
Y1365768D03*
X1109199Y1337422D03*
Y1351595D03*
Y1365768D03*
X1113530Y1337422D03*
Y1351595D03*
Y1365768D03*
X1119042Y1337422D03*
Y1351595D03*
Y1365768D03*
X1123372Y1337422D03*
Y1351595D03*
Y1365768D03*
X1127703Y1337422D03*
Y1351595D03*
Y1365768D03*
X1133215Y1337422D03*
Y1351595D03*
Y1365768D03*
X1091089Y1387028D03*
Y1401201D03*
X1095420Y1387028D03*
Y1401201D03*
X1100932Y1387028D03*
Y1401201D03*
X1105262Y1387028D03*
Y1401201D03*
X1109593Y1387028D03*
Y1401201D03*
X1115105Y1387028D03*
Y1401201D03*
X1119435Y1387028D03*
Y1401201D03*
X1123766Y1387028D03*
Y1401201D03*
X1129278Y1387028D03*
Y1401201D03*
X1133609Y1387028D03*
Y1401201D03*
X1095026Y1379942D03*
Y1394115D03*
Y1408288D03*
X1099357Y1379942D03*
Y1394115D03*
Y1408288D03*
X1104869Y1379942D03*
Y1394115D03*
Y1408288D03*
X1109199Y1379942D03*
Y1394115D03*
Y1408288D03*
X1113530Y1379942D03*
Y1394115D03*
Y1408288D03*
X1119042Y1379942D03*
Y1394115D03*
Y1408288D03*
X1123372Y1379942D03*
Y1394115D03*
Y1408288D03*
X1127703Y1379942D03*
Y1394115D03*
Y1408288D03*
X1133215Y1379942D03*
Y1394115D03*
Y1408288D03*
X1398228Y63977D03*
Y68307D03*
X1412402Y63977D03*
X1426575D03*
X1405315Y67914D03*
X1419488D03*
X1426575Y68307D03*
X1412402D03*
X1398228Y116339D03*
Y92323D03*
Y96654D03*
Y102166D03*
Y106496D03*
Y110827D03*
Y87993D03*
Y82481D03*
Y78150D03*
Y73819D03*
X1412402Y116339D03*
X1426575D03*
X1405315Y114764D03*
X1419488D03*
X1405315Y82087D03*
X1419488D03*
X1412402Y92323D03*
X1426575D03*
X1412402Y96654D03*
X1426575D03*
X1405315Y96260D03*
X1419488D03*
X1412402Y102166D03*
X1426575D03*
X1405315Y100591D03*
X1419488D03*
X1412402Y106496D03*
X1426575D03*
X1405315Y106103D03*
X1419488D03*
X1412402Y110827D03*
X1426575D03*
X1405315Y110433D03*
X1419488D03*
X1426575Y87993D03*
Y82481D03*
X1419488Y91930D03*
Y86418D03*
X1412402Y87993D03*
Y82481D03*
X1405315Y91930D03*
Y86418D03*
X1412402Y78150D03*
X1426575D03*
Y73819D03*
X1419488Y77756D03*
Y72245D03*
X1412402Y73819D03*
X1405315Y77756D03*
Y72245D03*
X1398228Y120670D03*
X1412402D03*
X1426575D03*
X1405315Y120276D03*
X1419488D03*
X1433661Y67914D03*
X1440748Y63977D03*
X1447835Y67914D03*
X1440748Y68307D03*
X1433661Y114764D03*
X1440748Y116339D03*
X1447835Y114764D03*
X1433661Y82087D03*
Y96260D03*
Y100591D03*
Y106103D03*
Y110433D03*
X1447835Y82087D03*
X1440748Y92323D03*
Y96654D03*
X1447835Y96260D03*
X1440748Y102166D03*
X1447835Y100591D03*
X1440748Y106496D03*
X1447835Y106103D03*
X1440748Y110827D03*
X1447835Y110433D03*
Y91930D03*
Y86418D03*
X1440748Y87993D03*
Y82481D03*
X1433661Y91930D03*
Y86418D03*
X1440748Y78150D03*
X1447835Y77756D03*
Y72245D03*
X1440748Y73819D03*
X1433661Y77756D03*
Y72245D03*
Y120276D03*
X1440748Y120670D03*
X1447835Y120276D03*
X1483268Y63977D03*
Y68307D03*
X1518701Y67914D03*
X1504528D03*
X1490354D03*
X1511614Y63977D03*
X1497441D03*
X1511614Y68307D03*
X1497441D03*
X1483268Y116339D03*
Y110827D03*
Y106496D03*
Y102166D03*
Y96654D03*
Y92323D03*
Y87993D03*
Y82481D03*
Y78150D03*
Y73819D03*
X1518701Y114764D03*
X1504528D03*
X1490354D03*
X1511614Y116339D03*
X1497441D03*
X1518701Y110433D03*
X1504528D03*
X1490354D03*
X1511614Y110827D03*
X1497441D03*
X1518701Y106103D03*
X1504528D03*
X1490354D03*
X1511614Y106496D03*
X1497441D03*
X1518701Y100591D03*
X1504528D03*
X1490354D03*
X1511614Y102166D03*
X1497441D03*
X1518701Y96260D03*
X1504528D03*
X1490354D03*
X1511614Y96654D03*
X1497441D03*
X1511614Y92323D03*
X1497441D03*
X1518701Y82087D03*
X1504528D03*
X1490354D03*
X1518701Y91930D03*
Y86418D03*
X1511614Y87993D03*
Y82481D03*
X1504528Y91930D03*
Y86418D03*
X1497441Y87993D03*
Y82481D03*
X1490354Y91930D03*
Y86418D03*
X1511614Y78150D03*
X1497441D03*
X1518701Y77756D03*
Y72245D03*
X1511614Y73819D03*
X1504528Y77756D03*
Y72245D03*
X1497441Y73819D03*
X1490354Y77756D03*
Y72245D03*
X1483268Y120670D03*
X1518701Y120276D03*
X1504528D03*
X1490354D03*
X1511614Y120670D03*
X1497441D03*
X1532874Y67914D03*
X1525787Y63977D03*
Y68307D03*
X1532874Y114764D03*
X1525787Y116339D03*
X1532874Y110433D03*
X1525787Y110827D03*
X1532874Y106103D03*
X1525787Y106496D03*
X1532874Y100591D03*
X1525787Y102166D03*
X1532874Y96260D03*
X1525787Y96654D03*
Y92323D03*
X1532874Y82087D03*
Y91930D03*
Y86418D03*
X1525787Y87993D03*
Y82481D03*
Y78150D03*
X1532874Y77756D03*
Y72245D03*
X1525787Y73819D03*
X1532874Y120276D03*
X1525787Y120670D03*
G54D59*
X736988Y885549D03*
X724776D03*
X736988Y891455D03*
X724776D03*
G54D68*
X720782Y927445D03*
Y905559D03*
G54D77*
X929331Y16536D03*
X937205Y20473D03*
Y12599D03*
X929331Y63780D03*
X937205Y67717D03*
X929331Y48032D03*
Y40158D03*
Y32284D03*
Y24410D03*
X937205Y51969D03*
Y44095D03*
Y36221D03*
Y28347D03*
X929331Y111024D03*
Y103150D03*
Y95276D03*
Y87402D03*
Y79528D03*
Y71654D03*
X937205Y114961D03*
Y107087D03*
Y99213D03*
Y91339D03*
Y83465D03*
Y75591D03*
X929331Y166142D03*
Y158268D03*
Y150394D03*
Y142520D03*
Y134646D03*
Y126772D03*
Y118898D03*
X937205Y162205D03*
Y154331D03*
Y146457D03*
Y138583D03*
Y130709D03*
Y122835D03*
X929331Y213386D03*
Y205512D03*
Y197638D03*
Y189764D03*
Y181890D03*
Y174016D03*
X937205Y209449D03*
Y201575D03*
Y193701D03*
Y185827D03*
Y177953D03*
Y170079D03*
X929331Y260630D03*
Y252756D03*
Y244882D03*
Y237008D03*
Y229134D03*
Y221260D03*
X937205Y256693D03*
Y248819D03*
Y240945D03*
Y233071D03*
Y225197D03*
Y217323D03*
X929331Y307874D03*
Y300000D03*
Y292126D03*
Y284252D03*
Y276378D03*
Y268504D03*
X937205Y303937D03*
Y296063D03*
Y288189D03*
Y280315D03*
Y272441D03*
Y264567D03*
X929331Y339371D03*
Y331496D03*
Y323622D03*
Y315748D03*
X937205Y335434D03*
Y327559D03*
Y319685D03*
Y311811D03*
X929331Y403543D03*
Y395669D03*
X937205Y407480D03*
Y399606D03*
Y391732D03*
X929331Y450787D03*
Y442913D03*
X937205Y454724D03*
Y446850D03*
X929331Y427165D03*
Y419291D03*
Y411417D03*
X937205Y431102D03*
Y423228D03*
Y415354D03*
X929331Y498031D03*
Y490157D03*
Y482283D03*
Y474409D03*
Y466535D03*
Y458661D03*
X937205Y501968D03*
Y494094D03*
Y486220D03*
Y478346D03*
Y470472D03*
Y462598D03*
X929331Y553149D03*
Y545275D03*
Y537401D03*
Y529527D03*
Y521653D03*
Y513779D03*
Y505905D03*
X937205Y549212D03*
Y541338D03*
Y533464D03*
Y525590D03*
Y517716D03*
Y509842D03*
X929331Y600393D03*
Y592519D03*
Y584645D03*
Y576771D03*
Y568897D03*
Y561023D03*
X937205Y596456D03*
Y588582D03*
Y580708D03*
Y572834D03*
Y564960D03*
Y557086D03*
X929331Y647637D03*
Y639763D03*
Y631889D03*
Y624015D03*
Y616141D03*
Y608267D03*
X937205Y643700D03*
Y635826D03*
Y627952D03*
Y620078D03*
Y612204D03*
Y604330D03*
X929331Y694881D03*
Y687007D03*
Y679133D03*
Y671259D03*
Y663385D03*
Y655511D03*
X937205Y690944D03*
Y683070D03*
Y675196D03*
Y667322D03*
Y659448D03*
Y651574D03*
X929331Y718504D03*
Y710629D03*
Y702755D03*
X937205Y714567D03*
Y706692D03*
Y698818D03*
X954921Y16536D03*
X947047Y20473D03*
Y12599D03*
X954921Y63780D03*
X947047Y67717D03*
X954921Y48032D03*
Y40158D03*
Y32284D03*
Y24410D03*
X947047Y51969D03*
Y44095D03*
Y36221D03*
Y28347D03*
X954921Y111024D03*
Y103150D03*
Y95276D03*
Y87402D03*
Y79528D03*
Y71654D03*
X947047Y114961D03*
Y107087D03*
Y99213D03*
Y91339D03*
Y83465D03*
Y75591D03*
X954921Y166142D03*
Y158268D03*
Y150394D03*
Y142520D03*
Y134646D03*
Y126772D03*
Y118898D03*
X947047Y162205D03*
Y154331D03*
Y146457D03*
Y138583D03*
Y130709D03*
Y122835D03*
X954921Y213386D03*
Y205512D03*
Y197638D03*
Y189764D03*
Y181890D03*
Y174016D03*
X947047Y209449D03*
Y201575D03*
Y193701D03*
Y185827D03*
Y177953D03*
Y170079D03*
X954921Y260630D03*
Y252756D03*
Y244882D03*
Y237008D03*
Y229134D03*
Y221260D03*
X947047Y256693D03*
Y248819D03*
Y240945D03*
Y233071D03*
Y225197D03*
Y217323D03*
X954921Y307874D03*
Y300000D03*
Y292126D03*
Y284252D03*
Y276378D03*
Y268504D03*
X947047Y303937D03*
Y296063D03*
Y288189D03*
Y280315D03*
Y272441D03*
Y264567D03*
X954921Y339371D03*
Y331496D03*
Y323622D03*
Y315748D03*
X947047Y335434D03*
Y327559D03*
Y319685D03*
Y311811D03*
X954921Y403543D03*
Y395669D03*
X947047Y407480D03*
Y399606D03*
Y391732D03*
X954921Y450787D03*
Y442913D03*
X947047Y454724D03*
Y446850D03*
X954921Y427165D03*
Y419291D03*
Y411417D03*
X947047Y431102D03*
Y423228D03*
Y415354D03*
X954921Y498031D03*
Y490157D03*
Y482283D03*
Y474409D03*
Y466535D03*
Y458661D03*
X947047Y501968D03*
Y494094D03*
Y486220D03*
Y478346D03*
Y470472D03*
Y462598D03*
X954921Y553149D03*
Y545275D03*
Y537401D03*
Y529527D03*
Y521653D03*
Y513779D03*
Y505905D03*
X947047Y549212D03*
Y541338D03*
Y533464D03*
Y525590D03*
Y517716D03*
Y509842D03*
X954921Y600393D03*
Y592519D03*
Y584645D03*
Y576771D03*
Y568897D03*
Y561023D03*
X947047Y596456D03*
Y588582D03*
Y580708D03*
Y572834D03*
Y564960D03*
Y557086D03*
X954921Y647637D03*
Y639763D03*
Y631889D03*
Y624015D03*
Y616141D03*
Y608267D03*
X947047Y643700D03*
Y635826D03*
Y627952D03*
Y620078D03*
Y612204D03*
Y604330D03*
X954921Y694881D03*
Y687007D03*
Y679133D03*
Y671259D03*
Y663385D03*
Y655511D03*
X947047Y690944D03*
Y683070D03*
Y675196D03*
Y667322D03*
Y659448D03*
Y651574D03*
X954921Y718504D03*
Y710629D03*
Y702755D03*
X947047Y714567D03*
Y706692D03*
Y698818D03*
X1123031Y16536D03*
X1097441D03*
X1115157Y20473D03*
Y12599D03*
X1105315Y20473D03*
Y12599D03*
X1123031Y63780D03*
X1097441D03*
X1115157Y67717D03*
X1105315D03*
X1123031Y48032D03*
Y40158D03*
Y32284D03*
Y24410D03*
X1097441Y48032D03*
Y40158D03*
Y32284D03*
Y24410D03*
X1115157Y51969D03*
Y44095D03*
Y36221D03*
Y28347D03*
X1105315Y51969D03*
Y44095D03*
Y36221D03*
Y28347D03*
X1123031Y111024D03*
Y103150D03*
Y95276D03*
Y87402D03*
Y79528D03*
Y71654D03*
X1097441Y111024D03*
Y103150D03*
Y95276D03*
Y87402D03*
Y79528D03*
Y71654D03*
X1115157Y114961D03*
Y107087D03*
Y99213D03*
Y91339D03*
Y83465D03*
Y75591D03*
X1105315Y114961D03*
Y107087D03*
Y99213D03*
Y91339D03*
Y83465D03*
Y75591D03*
X1123031Y166142D03*
Y158268D03*
Y150394D03*
Y142520D03*
Y134646D03*
Y126772D03*
Y118898D03*
X1097441Y166142D03*
Y158268D03*
Y150394D03*
Y142520D03*
Y134646D03*
Y126772D03*
Y118898D03*
X1115157Y162205D03*
Y154331D03*
Y146457D03*
Y138583D03*
Y130709D03*
Y122835D03*
X1105315Y162205D03*
Y154331D03*
Y146457D03*
Y138583D03*
Y130709D03*
Y122835D03*
X1123031Y213386D03*
Y205512D03*
Y197638D03*
Y189764D03*
Y181890D03*
Y174016D03*
X1097441Y213386D03*
Y205512D03*
Y197638D03*
Y189764D03*
Y181890D03*
Y174016D03*
X1115157Y209449D03*
Y201575D03*
Y193701D03*
Y185827D03*
Y177953D03*
Y170079D03*
X1105315Y209449D03*
Y201575D03*
Y193701D03*
Y185827D03*
Y177953D03*
Y170079D03*
X1123031Y260630D03*
Y252756D03*
Y244882D03*
Y237008D03*
Y229134D03*
Y221260D03*
X1097441Y260630D03*
Y252756D03*
Y244882D03*
Y237008D03*
Y229134D03*
Y221260D03*
X1115157Y256693D03*
Y248819D03*
Y240945D03*
Y233071D03*
Y225197D03*
Y217323D03*
X1105315Y256693D03*
Y248819D03*
Y240945D03*
Y233071D03*
Y225197D03*
Y217323D03*
X1123031Y307874D03*
Y300000D03*
Y292126D03*
Y284252D03*
Y276378D03*
Y268504D03*
X1097441Y307874D03*
Y300000D03*
Y292126D03*
Y284252D03*
Y276378D03*
Y268504D03*
X1115157Y303937D03*
Y296063D03*
Y288189D03*
Y280315D03*
Y272441D03*
Y264567D03*
X1105315Y303937D03*
Y296063D03*
Y288189D03*
Y280315D03*
Y272441D03*
Y264567D03*
X1123031Y339371D03*
Y331496D03*
Y323622D03*
Y315748D03*
X1097441Y339371D03*
Y331496D03*
Y323622D03*
Y315748D03*
X1115157Y335434D03*
Y327559D03*
Y319685D03*
Y311811D03*
X1105315Y335434D03*
Y327559D03*
Y319685D03*
Y311811D03*
X1123031Y403543D03*
Y395669D03*
X1097441Y403543D03*
Y395669D03*
X1115157Y407480D03*
Y399606D03*
Y391732D03*
X1105315Y407480D03*
Y399606D03*
Y391732D03*
X1123031Y450787D03*
Y442913D03*
X1097441Y450787D03*
Y442913D03*
X1115157Y454724D03*
Y446850D03*
X1105315Y454724D03*
Y446850D03*
X1123031Y427165D03*
Y419291D03*
Y411417D03*
X1097441Y427165D03*
Y419291D03*
Y411417D03*
X1115157Y431102D03*
Y423228D03*
Y415354D03*
X1105315Y431102D03*
Y423228D03*
Y415354D03*
X1123031Y498031D03*
Y490157D03*
Y482283D03*
Y474409D03*
Y466535D03*
Y458661D03*
X1097441Y498031D03*
Y490157D03*
Y482283D03*
Y474409D03*
Y466535D03*
Y458661D03*
X1115157Y501968D03*
Y494094D03*
Y486220D03*
Y478346D03*
Y470472D03*
Y462598D03*
X1105315Y501968D03*
Y494094D03*
Y486220D03*
Y478346D03*
Y470472D03*
Y462598D03*
X1123031Y553149D03*
Y545275D03*
Y537401D03*
Y529527D03*
Y521653D03*
Y513779D03*
Y505905D03*
X1097441Y553149D03*
Y545275D03*
Y537401D03*
Y529527D03*
Y521653D03*
Y513779D03*
Y505905D03*
X1115157Y549212D03*
Y541338D03*
Y533464D03*
Y525590D03*
Y517716D03*
Y509842D03*
X1105315Y549212D03*
Y541338D03*
Y533464D03*
Y525590D03*
Y517716D03*
Y509842D03*
X1123031Y600393D03*
Y592519D03*
Y584645D03*
Y576771D03*
Y568897D03*
Y561023D03*
X1097441Y600393D03*
Y592519D03*
Y584645D03*
Y576771D03*
Y568897D03*
Y561023D03*
X1115157Y596456D03*
Y588582D03*
Y580708D03*
Y572834D03*
Y564960D03*
Y557086D03*
X1105315Y596456D03*
Y588582D03*
Y580708D03*
Y572834D03*
Y564960D03*
Y557086D03*
X1123031Y647637D03*
Y639763D03*
Y631889D03*
Y624015D03*
Y616141D03*
Y608267D03*
X1097441Y647637D03*
Y639763D03*
Y631889D03*
Y624015D03*
Y616141D03*
Y608267D03*
X1115157Y643700D03*
Y635826D03*
Y627952D03*
Y620078D03*
Y612204D03*
Y604330D03*
X1105315Y643700D03*
Y635826D03*
Y627952D03*
Y620078D03*
Y612204D03*
Y604330D03*
X1123031Y694881D03*
Y687007D03*
Y679133D03*
Y671259D03*
Y663385D03*
Y655511D03*
X1097441Y694881D03*
Y687007D03*
Y679133D03*
Y671259D03*
Y663385D03*
Y655511D03*
X1115157Y690944D03*
Y683070D03*
Y675196D03*
Y667322D03*
Y659448D03*
Y651574D03*
X1105315Y690944D03*
Y683070D03*
Y675196D03*
Y667322D03*
Y659448D03*
Y651574D03*
X1123031Y718504D03*
Y710629D03*
Y702755D03*
X1097441Y718504D03*
Y710629D03*
Y702755D03*
X1115157Y714567D03*
Y706692D03*
Y698818D03*
X1105315Y714567D03*
Y706692D03*
Y698818D03*
G54D78*
X942126Y58465D03*
Y346457D03*
Y437598D03*
Y725590D03*
X1110236Y58465D03*
Y346457D03*
Y437598D03*
Y725590D03*
G54D69*
X744633Y924689D03*
X744133D03*
X1858126Y800787D03*
X1858626D03*
G54D79*
X986614Y1619764D03*
X974016D03*
Y1597126D03*
X986614D03*
X974016Y1591220D03*
Y1603031D03*
Y1613858D03*
X986614Y1591220D03*
Y1613858D03*
Y1603031D03*
X974016Y1642401D03*
X986614D03*
X974016Y1625669D03*
Y1636496D03*
Y1648307D03*
X986614Y1625669D03*
Y1636496D03*
Y1648307D03*
X1030709Y1619764D03*
X1014961D03*
X1002362D03*
Y1597126D03*
X1014961D03*
X1030709D03*
X1002362Y1591220D03*
Y1603031D03*
Y1613858D03*
X1014961Y1591220D03*
Y1603031D03*
Y1613858D03*
X1030709Y1591220D03*
Y1613858D03*
Y1603031D03*
X1002362Y1642401D03*
X1014961D03*
X1030709D03*
X1002362Y1625669D03*
Y1636496D03*
Y1648307D03*
X1014961Y1625669D03*
Y1636496D03*
Y1648307D03*
X1030709Y1625669D03*
Y1636496D03*
Y1648307D03*
X1043307Y1619764D03*
Y1597126D03*
Y1591220D03*
Y1603031D03*
Y1613858D03*
Y1642401D03*
Y1625669D03*
Y1636496D03*
Y1648307D03*
X1101457Y1588583D03*
X1119685D03*
X1101457Y1601181D03*
X1119685D03*
X1108150Y1588583D03*
X1126378D03*
X1108150Y1601181D03*
X1126378D03*
M02*
